G04*
G04 #@! TF.GenerationSoftware,Altium Limited,Altium Designer,23.7.1 (13)*
G04*
G04 Layer_Color=8388736*
%FSLAX25Y25*%
%MOIN*%
G70*
G04*
G04 #@! TF.SameCoordinates,AF00DCEB-AC48-4C7C-91EA-99F42E284231*
G04*
G04*
G04 #@! TF.FilePolarity,Negative*
G04*
G01*
G75*
%ADD32C,0.02500*%
%ADD44R,0.03543X0.02953*%
%ADD45R,0.03543X0.03150*%
%ADD49R,0.05512X0.03937*%
%ADD50R,0.03543X0.03937*%
%ADD51C,0.02918*%
%ADD52R,0.01457X0.00945*%
%ADD53R,0.01575X0.04252*%
%ADD54R,0.07835X0.09173*%
%ADD61R,0.03150X0.03150*%
%ADD62R,0.05000X0.02992*%
%ADD65R,0.07100X0.07100*%
%ADD66R,0.01000X0.03200*%
%ADD67R,0.03200X0.01000*%
%ADD70R,0.06102X0.01181*%
%ADD71R,0.10827X0.04724*%
%ADD72R,0.01181X0.06102*%
%ADD73R,0.04724X0.10827*%
%ADD74R,0.09800X0.03700*%
%ADD75R,0.23300X0.21700*%
%ADD78R,0.05100X0.03500*%
%ADD79R,0.08300X0.03500*%
%ADD80R,0.08300X0.07400*%
%ADD81R,0.02600X0.07400*%
%ADD82R,0.01400X0.07400*%
%ADD83R,0.02000X0.01300*%
%ADD84R,0.01300X0.02000*%
%ADD85R,0.09173X0.07835*%
%ADD86R,0.02816X0.02648*%
%ADD87R,0.02016X0.02288*%
%ADD88R,0.02911X0.02648*%
%ADD89R,0.02756X0.02756*%
G04:AMPARAMS|DCode=90|XSize=40.88mil|YSize=20.95mil|CornerRadius=10.48mil|HoleSize=0mil|Usage=FLASHONLY|Rotation=270.000|XOffset=0mil|YOffset=0mil|HoleType=Round|Shape=RoundedRectangle|*
%AMROUNDEDRECTD90*
21,1,0.04088,0.00000,0,0,270.0*
21,1,0.01993,0.02095,0,0,270.0*
1,1,0.02095,0.00000,-0.00996*
1,1,0.02095,0.00000,0.00996*
1,1,0.02095,0.00000,0.00996*
1,1,0.02095,0.00000,-0.00996*
%
%ADD90ROUNDEDRECTD90*%
%ADD91R,0.02095X0.04088*%
G04:AMPARAMS|DCode=92|XSize=61.02mil|YSize=23.62mil|CornerRadius=2.01mil|HoleSize=0mil|Usage=FLASHONLY|Rotation=90.000|XOffset=0mil|YOffset=0mil|HoleType=Round|Shape=RoundedRectangle|*
%AMROUNDEDRECTD92*
21,1,0.06102,0.01961,0,0,90.0*
21,1,0.05701,0.02362,0,0,90.0*
1,1,0.00402,0.00980,0.02850*
1,1,0.00402,0.00980,-0.02850*
1,1,0.00402,-0.00980,-0.02850*
1,1,0.00402,-0.00980,0.02850*
%
%ADD92ROUNDEDRECTD92*%
G04:AMPARAMS|DCode=94|XSize=61.02mil|YSize=23.62mil|CornerRadius=2.01mil|HoleSize=0mil|Usage=FLASHONLY|Rotation=0.000|XOffset=0mil|YOffset=0mil|HoleType=Round|Shape=RoundedRectangle|*
%AMROUNDEDRECTD94*
21,1,0.06102,0.01961,0,0,0.0*
21,1,0.05701,0.02362,0,0,0.0*
1,1,0.00402,0.02850,-0.00980*
1,1,0.00402,-0.02850,-0.00980*
1,1,0.00402,-0.02850,0.00980*
1,1,0.00402,0.02850,0.00980*
%
%ADD94ROUNDEDRECTD94*%
%ADD95R,0.04546X0.06717*%
%ADD96R,0.03500X0.05100*%
%ADD97R,0.03500X0.08300*%
%ADD98R,0.07400X0.08300*%
%ADD99R,0.07400X0.02600*%
%ADD100R,0.07400X0.01400*%
%ADD101R,0.06717X0.04546*%
%ADD102R,0.04331X0.05315*%
%ADD103R,0.07874X0.11811*%
%ADD104R,0.11811X0.07874*%
%ADD105R,0.02631X0.02648*%
%ADD111R,0.07480X0.04331*%
%ADD113R,0.02648X0.02911*%
%ADD120R,0.02288X0.02016*%
%ADD124R,0.02648X0.02816*%
%ADD125R,0.01378X0.01968*%
%ADD128R,0.01870X0.01968*%
G04:AMPARAMS|DCode=129|XSize=33.06mil|YSize=8.76mil|CornerRadius=4.38mil|HoleSize=0mil|Usage=FLASHONLY|Rotation=90.000|XOffset=0mil|YOffset=0mil|HoleType=Round|Shape=RoundedRectangle|*
%AMROUNDEDRECTD129*
21,1,0.03306,0.00000,0,0,90.0*
21,1,0.02430,0.00876,0,0,90.0*
1,1,0.00876,0.00000,0.01215*
1,1,0.00876,0.00000,-0.01215*
1,1,0.00876,0.00000,-0.01215*
1,1,0.00876,0.00000,0.01215*
%
%ADD129ROUNDEDRECTD129*%
%ADD130R,0.00876X0.03306*%
%ADD131R,0.05142X0.04166*%
%ADD132R,0.01968X0.01968*%
%ADD133R,0.09449X0.12992*%
%ADD145R,0.01181X0.02067*%
%ADD146R,0.01181X0.02067*%
%ADD147R,0.02067X0.01575*%
%ADD148R,0.02067X0.01575*%
%ADD149R,0.31496X0.13583*%
%ADD150R,1.35433X0.23032*%
%ADD151R,0.13595X0.13595*%
%ADD152R,0.01824X0.04343*%
%ADD153R,0.04343X0.01824*%
%ADD154R,0.04540X0.04540*%
%ADD155R,0.02572X0.02572*%
%ADD156R,0.05131X0.04934*%
%ADD157R,0.04934X0.05131*%
%ADD158R,0.06509X0.05328*%
%ADD159R,0.06509X0.08280*%
G04:AMPARAMS|DCode=160|XSize=19.81mil|YSize=37.53mil|CornerRadius=5.95mil|HoleSize=0mil|Usage=FLASHONLY|Rotation=180.000|XOffset=0mil|YOffset=0mil|HoleType=Round|Shape=RoundedRectangle|*
%AMROUNDEDRECTD160*
21,1,0.01981,0.02563,0,0,180.0*
21,1,0.00791,0.03753,0,0,180.0*
1,1,0.01190,-0.00396,0.01282*
1,1,0.01190,0.00396,0.01282*
1,1,0.01190,0.00396,-0.01282*
1,1,0.01190,-0.00396,-0.01282*
%
%ADD160ROUNDEDRECTD160*%
G04:AMPARAMS|DCode=161|XSize=19.81mil|YSize=37.53mil|CornerRadius=5.95mil|HoleSize=0mil|Usage=FLASHONLY|Rotation=90.000|XOffset=0mil|YOffset=0mil|HoleType=Round|Shape=RoundedRectangle|*
%AMROUNDEDRECTD161*
21,1,0.01981,0.02563,0,0,90.0*
21,1,0.00791,0.03753,0,0,90.0*
1,1,0.01190,0.01282,0.00396*
1,1,0.01190,0.01282,-0.00396*
1,1,0.01190,-0.01282,-0.00396*
1,1,0.01190,-0.01282,0.00396*
%
%ADD161ROUNDEDRECTD161*%
G04:AMPARAMS|DCode=162|XSize=90.68mil|YSize=90.68mil|CornerRadius=6.07mil|HoleSize=0mil|Usage=FLASHONLY|Rotation=90.000|XOffset=0mil|YOffset=0mil|HoleType=Round|Shape=RoundedRectangle|*
%AMROUNDEDRECTD162*
21,1,0.09068,0.07854,0,0,90.0*
21,1,0.07854,0.09068,0,0,90.0*
1,1,0.01213,0.03927,0.03927*
1,1,0.01213,0.03927,-0.03927*
1,1,0.01213,-0.03927,-0.03927*
1,1,0.01213,-0.03927,0.03927*
%
%ADD162ROUNDEDRECTD162*%
%ADD163R,0.06115X0.02375*%
%ADD164R,0.08280X0.07887*%
%ADD165R,0.09087X0.05209*%
%ADD166R,0.02769X0.02572*%
%ADD167R,0.10400X0.05200*%
%ADD168R,0.02965X0.02965*%
%ADD169R,0.02362X0.00787*%
%ADD170R,0.00787X0.02362*%
%ADD171C,0.00709*%
%ADD172R,0.02572X0.02769*%
%ADD173R,0.02965X0.02965*%
%ADD174R,0.00787X0.02362*%
%ADD175R,0.02362X0.00787*%
%ADD176R,0.06706X0.08083*%
%ADD177R,0.03359X0.03162*%
%ADD178R,0.01784X0.06902*%
%ADD179R,0.06115X0.07493*%
%ADD180O,0.03162X0.09461*%
%ADD181O,0.03162X0.08280*%
%ADD182R,0.03635X0.03635*%
%ADD183R,0.05209X0.09087*%
%ADD184R,0.04343X0.02769*%
%ADD185R,0.04540X0.06509*%
%ADD186R,0.04934X0.04737*%
%ADD187R,0.09461X0.04934*%
%ADD188R,0.03162X0.03359*%
%ADD189R,0.04737X0.06312*%
%ADD190R,0.06312X0.06312*%
%ADD191R,0.15288X0.05800*%
%ADD192R,0.04343X0.03162*%
%ADD193R,0.02965X0.03162*%
%ADD194R,0.10039X0.06496*%
%ADD195R,0.07493X0.06115*%
%ADD196R,0.06902X0.01784*%
%ADD197R,0.07887X0.01784*%
%ADD198R,0.08280X0.06509*%
%ADD199R,0.04147X0.01981*%
%ADD200R,0.04343X0.03556*%
%ADD201R,0.03556X0.04343*%
%ADD202R,0.03600X0.17300*%
%ADD203R,0.03600X0.13400*%
%ADD204R,0.04737X0.03635*%
%ADD205R,0.08280X0.07001*%
%ADD206C,0.06902*%
%ADD207R,0.06902X0.06902*%
%ADD208C,0.07099*%
%ADD209R,0.07099X0.07099*%
%ADD210C,0.11800*%
%ADD211R,0.10827X0.10827*%
%ADD212C,0.10827*%
%ADD213C,0.25800*%
%ADD214O,0.05721X0.04934*%
%ADD215O,0.08280X0.05524*%
%ADD216C,0.00800*%
%ADD217C,0.06299*%
%ADD218C,0.04331*%
%ADD219C,0.26391*%
%ADD220C,0.02966*%
%ADD221C,0.10800*%
%ADD222C,0.24800*%
%ADD223R,0.00800X0.00800*%
%ADD224C,0.09461*%
%ADD225R,0.08674X0.08674*%
%ADD226R,0.06706X0.06706*%
%ADD227C,0.06706*%
%ADD228C,0.02400*%
%ADD229C,0.20800*%
G36*
X510775Y14879D02*
X510827Y14869D01*
X510877Y14852D01*
X510880Y14850D01*
X511046D01*
X511098Y14847D01*
X511150Y14837D01*
X511199Y14820D01*
X511203Y14818D01*
X511207D01*
X511259Y14815D01*
X511311Y14804D01*
X511360Y14787D01*
X511368Y14784D01*
X511388Y14782D01*
X511440Y14772D01*
X511489Y14755D01*
X511537Y14732D01*
X511546Y14726D01*
X511554Y14723D01*
X511575Y14713D01*
X511601Y14708D01*
X511651Y14691D01*
X511698Y14668D01*
X511707Y14661D01*
X511715Y14658D01*
X511736Y14648D01*
X511762Y14643D01*
X511812Y14626D01*
X511859Y14603D01*
X511903Y14574D01*
X511927Y14553D01*
X511956Y14538D01*
X511965Y14532D01*
X511973Y14529D01*
X512020Y14506D01*
X512064Y14477D01*
X512088Y14456D01*
X512117Y14442D01*
X512161Y14412D01*
X512185Y14392D01*
X512208Y14380D01*
X512214Y14377D01*
X512258Y14348D01*
X512297Y14313D01*
X512312Y14296D01*
X512329Y14281D01*
X512344Y14264D01*
X512361Y14249D01*
X512377Y14232D01*
X512394Y14217D01*
X512409Y14199D01*
X512426Y14184D01*
X512441Y14167D01*
X512458Y14152D01*
X512473Y14135D01*
X512491Y14120D01*
X512506Y14103D01*
X512523Y14088D01*
X512538Y14070D01*
X512555Y14055D01*
X512570Y14038D01*
X512580Y14030D01*
X512587Y14023D01*
X512602Y14006D01*
X512612Y13998D01*
X512620Y13991D01*
X512635Y13974D01*
X512644Y13965D01*
X512652Y13959D01*
X512686Y13919D01*
X512716Y13876D01*
X512730Y13846D01*
X512751Y13822D01*
X512780Y13779D01*
X512795Y13749D01*
X512816Y13726D01*
X512845Y13682D01*
X512868Y13635D01*
X512871Y13627D01*
X512877Y13617D01*
X512891Y13588D01*
X512912Y13564D01*
X512941Y13521D01*
X512965Y13474D01*
X512967Y13466D01*
X512974Y13456D01*
X512997Y13409D01*
X513014Y13360D01*
X513019Y13333D01*
X513029Y13312D01*
X513032Y13304D01*
X513038Y13295D01*
X513061Y13248D01*
X513078Y13198D01*
X513084Y13171D01*
X513094Y13151D01*
X513110Y13101D01*
X513121Y13050D01*
X513122Y13030D01*
Y13030D01*
X513126Y13022D01*
X513143Y12972D01*
X513153Y12921D01*
X513154Y12901D01*
X513158Y12893D01*
X513175Y12843D01*
X513185Y12792D01*
X513189Y12740D01*
Y12707D01*
Y12675D01*
Y12643D01*
Y12610D01*
Y12578D01*
Y12574D01*
X513191Y12570D01*
X513207Y12521D01*
X513218Y12469D01*
X513221Y12417D01*
Y12385D01*
Y12352D01*
Y12320D01*
Y12288D01*
X513218Y12235D01*
X513207Y12184D01*
X513191Y12134D01*
X513189Y12131D01*
Y12127D01*
Y12094D01*
Y12062D01*
Y12030D01*
Y11998D01*
X513185Y11945D01*
X513175Y11894D01*
X513158Y11844D01*
X513157Y11841D01*
Y11836D01*
X513153Y11784D01*
X513143Y11733D01*
X513126Y11683D01*
X513116Y11662D01*
X513110Y11636D01*
X513094Y11586D01*
X513084Y11565D01*
X513078Y11539D01*
X513061Y11489D01*
X513051Y11469D01*
X513046Y11442D01*
X513029Y11392D01*
X513006Y11345D01*
X513000Y11336D01*
X512997Y11328D01*
X512974Y11281D01*
X512967Y11271D01*
X512965Y11263D01*
X512941Y11216D01*
X512935Y11207D01*
X512932Y11199D01*
X512909Y11152D01*
X512903Y11142D01*
X512900Y11134D01*
X512877Y11087D01*
X512871Y11078D01*
X512868Y11070D01*
X512845Y11023D01*
X512816Y10979D01*
X512795Y10955D01*
X512791Y10948D01*
X512780Y10926D01*
X512751Y10882D01*
X512716Y10843D01*
X512699Y10828D01*
X512698Y10826D01*
X512683Y10797D01*
X512654Y10753D01*
X512620Y10714D01*
X512602Y10699D01*
X512587Y10682D01*
X512570Y10667D01*
X512555Y10649D01*
X512538Y10634D01*
X512523Y10617D01*
X512506Y10602D01*
X512491Y10585D01*
X512473Y10570D01*
X512458Y10553D01*
X512441Y10538D01*
X512426Y10520D01*
X512409Y10505D01*
X512394Y10488D01*
X512377Y10473D01*
X512361Y10456D01*
X512322Y10421D01*
X512279Y10392D01*
X512249Y10378D01*
X512248Y10376D01*
X512232Y10359D01*
X512215Y10344D01*
X512200Y10327D01*
X512161Y10292D01*
X512117Y10263D01*
X512088Y10249D01*
X512064Y10228D01*
X512020Y10199D01*
X511973Y10175D01*
X511965Y10173D01*
X511956Y10166D01*
X511909Y10143D01*
X511901Y10140D01*
X511891Y10134D01*
X511844Y10111D01*
X511836Y10108D01*
X511827Y10102D01*
X511780Y10079D01*
X511772Y10076D01*
X511762Y10069D01*
X511715Y10046D01*
X511707Y10044D01*
X511698Y10037D01*
X511651Y10014D01*
X511601Y9997D01*
X511575Y9992D01*
X511554Y9982D01*
X511504Y9965D01*
X511478Y9960D01*
X511457Y9950D01*
X511408Y9933D01*
X511356Y9922D01*
X511336Y9921D01*
X511328Y9917D01*
X511278Y9900D01*
X511227Y9890D01*
X511175Y9887D01*
X511170D01*
X511167Y9885D01*
X511117Y9868D01*
X511066Y9858D01*
X511014Y9854D01*
X507884D01*
X507832Y9858D01*
X507780Y9868D01*
X507731Y9885D01*
X507727Y9887D01*
X507723D01*
X507670Y9890D01*
X507619Y9900D01*
X507569Y9917D01*
X507549Y9927D01*
X507522Y9933D01*
X507473Y9950D01*
X507452Y9960D01*
X507425Y9965D01*
X507376Y9982D01*
X507355Y9992D01*
X507329Y9997D01*
X507279Y10014D01*
X507232Y10037D01*
X507223Y10044D01*
X507214Y10046D01*
X507194Y10056D01*
X507167Y10062D01*
X507118Y10079D01*
X507071Y10102D01*
X507027Y10131D01*
X507003Y10152D01*
X506974Y10166D01*
X506964Y10173D01*
X506956Y10175D01*
X506909Y10199D01*
X506866Y10228D01*
X506842Y10249D01*
X506813Y10263D01*
X506769Y10292D01*
X506745Y10313D01*
X506716Y10328D01*
X506672Y10357D01*
X506633Y10391D01*
X506632Y10392D01*
X506618Y10408D01*
X506601Y10424D01*
X506585Y10441D01*
X506568Y10456D01*
X506553Y10473D01*
X506536Y10488D01*
X506521Y10505D01*
X506504Y10520D01*
X506489Y10538D01*
X506471Y10553D01*
X506456Y10570D01*
X506439Y10585D01*
X506438Y10586D01*
X506424Y10602D01*
X506407Y10617D01*
X506392Y10634D01*
X506375Y10649D01*
X506369Y10656D01*
X506360Y10667D01*
X506342Y10682D01*
X506327Y10699D01*
X506310Y10714D01*
X506295Y10731D01*
X506278Y10746D01*
X506243Y10786D01*
X506214Y10829D01*
X506200Y10859D01*
X506198Y10860D01*
X506181Y10875D01*
X506146Y10915D01*
X506117Y10958D01*
X506094Y11005D01*
X506091Y11013D01*
X506085Y11023D01*
X506071Y11052D01*
X506050Y11076D01*
X506021Y11120D01*
X505997Y11167D01*
X505995Y11175D01*
X505988Y11184D01*
X505965Y11231D01*
X505962Y11239D01*
X505956Y11249D01*
X505933Y11296D01*
X505930Y11304D01*
X505924Y11313D01*
X505901Y11360D01*
X505884Y11410D01*
X505878Y11436D01*
X505868Y11457D01*
X505852Y11507D01*
X505846Y11533D01*
X505836Y11554D01*
X505819Y11603D01*
X505814Y11630D01*
X505804Y11650D01*
X505787Y11700D01*
X505777Y11752D01*
X505773Y11804D01*
Y11808D01*
X505772Y11812D01*
X505755Y11862D01*
X505745Y11913D01*
X505741Y11965D01*
Y11970D01*
X505739Y11973D01*
X505723Y12023D01*
X505712Y12074D01*
X505709Y12127D01*
Y12159D01*
Y12191D01*
Y12223D01*
Y12256D01*
Y12288D01*
Y12320D01*
Y12352D01*
Y12385D01*
Y12417D01*
Y12449D01*
Y12481D01*
Y12514D01*
Y12546D01*
X505712Y12598D01*
X505723Y12650D01*
X505739Y12699D01*
X505741Y12703D01*
Y12707D01*
Y12740D01*
Y12772D01*
X505745Y12824D01*
X505755Y12876D01*
X505772Y12925D01*
X505775Y12933D01*
X505777Y12953D01*
X505787Y13005D01*
X505804Y13054D01*
X505808Y13062D01*
X505809Y13082D01*
X505819Y13134D01*
X505836Y13183D01*
X505859Y13230D01*
X505866Y13240D01*
X505868Y13248D01*
X505878Y13268D01*
X505884Y13295D01*
X505901Y13345D01*
X505924Y13392D01*
X505930Y13401D01*
X505933Y13409D01*
X505956Y13456D01*
X505962Y13466D01*
X505965Y13474D01*
X505988Y13521D01*
X505995Y13530D01*
X505997Y13538D01*
X506021Y13585D01*
X506027Y13595D01*
X506030Y13603D01*
X506053Y13650D01*
X506082Y13693D01*
X506103Y13717D01*
X506117Y13747D01*
X506146Y13790D01*
X506168Y13814D01*
X506182Y13843D01*
X506211Y13887D01*
X506246Y13926D01*
X506248Y13929D01*
X506263Y13941D01*
X506278Y13959D01*
X506286Y13965D01*
X506295Y13974D01*
X506310Y13991D01*
X506318Y13998D01*
X506327Y14006D01*
X506342Y14023D01*
X506360Y14038D01*
X506375Y14055D01*
X506392Y14070D01*
X506407Y14088D01*
X506424Y14103D01*
X506439Y14120D01*
X506457Y14135D01*
X506471Y14152D01*
X506489Y14167D01*
X506504Y14184D01*
X506521Y14199D01*
X506536Y14217D01*
X506553Y14232D01*
X506568Y14249D01*
X506585Y14264D01*
X506601Y14281D01*
X506618Y14296D01*
X506633Y14313D01*
X506650Y14329D01*
X506665Y14346D01*
X506704Y14380D01*
X506748Y14409D01*
X506754Y14412D01*
X506777Y14424D01*
X506801Y14445D01*
X506845Y14474D01*
X506874Y14488D01*
X506898Y14509D01*
X506942Y14538D01*
X506989Y14562D01*
X506997Y14564D01*
X507006Y14571D01*
X507053Y14594D01*
X507061Y14597D01*
X507071Y14603D01*
X507118Y14626D01*
X507126Y14629D01*
X507135Y14635D01*
X507182Y14658D01*
X507232Y14675D01*
X507259Y14681D01*
X507279Y14691D01*
X507287Y14693D01*
X507297Y14700D01*
X507343Y14723D01*
X507393Y14740D01*
X507420Y14745D01*
X507440Y14755D01*
X507490Y14772D01*
X507541Y14782D01*
X507561Y14784D01*
X507569Y14787D01*
X507619Y14804D01*
X507670Y14815D01*
X507691Y14816D01*
X507698Y14820D01*
X507748Y14837D01*
X507799Y14847D01*
X507852Y14850D01*
X508050D01*
X508053Y14852D01*
X508103Y14869D01*
X508154Y14879D01*
X508207Y14883D01*
X510659D01*
X510675Y14882D01*
X510691Y14883D01*
X510723D01*
X510775Y14879D01*
D02*
G37*
G36*
X518196Y-1962D02*
X518247Y-1972D01*
X518297Y-1989D01*
X518300Y-1990D01*
X518337D01*
X518389Y-1994D01*
X518441Y-2004D01*
X518490Y-2021D01*
X518498Y-2025D01*
X518518Y-2026D01*
X518570Y-2036D01*
X518619Y-2053D01*
X518640Y-2063D01*
X518667Y-2069D01*
X518716Y-2085D01*
X518737Y-2096D01*
X518763Y-2101D01*
X518813Y-2118D01*
X518860Y-2141D01*
X518869Y-2147D01*
X518877Y-2150D01*
X518898Y-2160D01*
X518925Y-2165D01*
X518974Y-2182D01*
X519021Y-2205D01*
X519031Y-2212D01*
X519039Y-2214D01*
X519086Y-2238D01*
X519129Y-2267D01*
X519153Y-2288D01*
X519176Y-2299D01*
X519182Y-2302D01*
X519192Y-2308D01*
X519200Y-2311D01*
X519247Y-2334D01*
X519291Y-2364D01*
X519314Y-2385D01*
X519344Y-2399D01*
X519387Y-2428D01*
X519427Y-2463D01*
X519442Y-2480D01*
X519459Y-2495D01*
X519474Y-2512D01*
X519476Y-2513D01*
X519489Y-2520D01*
X519505Y-2528D01*
X519549Y-2557D01*
X519588Y-2592D01*
X519603Y-2609D01*
X519620Y-2624D01*
X519635Y-2641D01*
X519653Y-2656D01*
X519668Y-2673D01*
X519685Y-2688D01*
X519700Y-2706D01*
X519717Y-2721D01*
X519732Y-2738D01*
X519749Y-2753D01*
X519765Y-2770D01*
X519782Y-2785D01*
X519797Y-2802D01*
X519814Y-2818D01*
X519849Y-2857D01*
X519878Y-2901D01*
X519892Y-2930D01*
X519894Y-2932D01*
X519911Y-2947D01*
X519945Y-2986D01*
X519975Y-3030D01*
X519989Y-3059D01*
X520010Y-3083D01*
X520039Y-3126D01*
X520062Y-3173D01*
X520065Y-3181D01*
X520071Y-3191D01*
X520086Y-3220D01*
X520088Y-3223D01*
X520107Y-3244D01*
X520136Y-3288D01*
X520159Y-3335D01*
X520162Y-3343D01*
X520168Y-3352D01*
X520191Y-3399D01*
X520208Y-3449D01*
X520211Y-3464D01*
X520213Y-3476D01*
X520224Y-3496D01*
X520226Y-3504D01*
X520233Y-3514D01*
X520256Y-3561D01*
X520273Y-3610D01*
X520278Y-3637D01*
X520288Y-3657D01*
X520305Y-3707D01*
X520310Y-3734D01*
X520320Y-3754D01*
X520337Y-3804D01*
X520347Y-3855D01*
X520349Y-3875D01*
X520353Y-3883D01*
X520369Y-3933D01*
X520380Y-3984D01*
X520383Y-4037D01*
Y-4069D01*
Y-4073D01*
X520385Y-4077D01*
X520402Y-4126D01*
X520412Y-4178D01*
X520415Y-4230D01*
Y-4262D01*
Y-4295D01*
Y-4327D01*
Y-4359D01*
Y-4391D01*
Y-4424D01*
Y-4456D01*
Y-4488D01*
Y-4521D01*
Y-4553D01*
Y-4585D01*
Y-4617D01*
Y-4650D01*
Y-4682D01*
Y-4714D01*
X520412Y-4766D01*
X520402Y-4818D01*
X520385Y-4868D01*
X520383Y-4871D01*
Y-4875D01*
Y-4908D01*
X520380Y-4960D01*
X520369Y-5011D01*
X520353Y-5061D01*
X520349Y-5069D01*
X520347Y-5089D01*
X520337Y-5141D01*
X520320Y-5190D01*
X520310Y-5211D01*
X520305Y-5237D01*
X520288Y-5287D01*
X520278Y-5307D01*
X520273Y-5334D01*
X520256Y-5384D01*
X520233Y-5431D01*
X520226Y-5440D01*
X520224Y-5448D01*
X520200Y-5495D01*
X520194Y-5505D01*
X520191Y-5513D01*
X520168Y-5560D01*
X520162Y-5569D01*
X520159Y-5577D01*
X520136Y-5624D01*
X520129Y-5634D01*
X520127Y-5642D01*
X520104Y-5689D01*
X520097Y-5698D01*
X520094Y-5706D01*
X520071Y-5753D01*
X520042Y-5797D01*
X520021Y-5821D01*
X520007Y-5850D01*
X519978Y-5894D01*
X519958Y-5915D01*
X519957Y-5918D01*
X519942Y-5947D01*
X519913Y-5991D01*
X519878Y-6030D01*
X519861Y-6045D01*
X519846Y-6062D01*
X519829Y-6077D01*
X519826Y-6081D01*
X519814Y-6094D01*
X519797Y-6109D01*
X519789Y-6118D01*
X519782Y-6127D01*
X519765Y-6142D01*
X519749Y-6159D01*
X519732Y-6174D01*
X519717Y-6191D01*
X519700Y-6206D01*
X519685Y-6224D01*
X519668Y-6239D01*
X519653Y-6256D01*
X519636Y-6271D01*
X519620Y-6288D01*
X519603Y-6303D01*
X519588Y-6320D01*
X519571Y-6335D01*
X519556Y-6352D01*
X519539Y-6368D01*
X519524Y-6384D01*
X519524Y-6385D01*
X519506Y-6400D01*
X519491Y-6417D01*
X519452Y-6452D01*
X519408Y-6481D01*
X519379Y-6495D01*
X519377Y-6497D01*
X519362Y-6514D01*
X519323Y-6548D01*
X519279Y-6577D01*
X519232Y-6601D01*
X519224Y-6604D01*
X519215Y-6610D01*
X519185Y-6624D01*
X519162Y-6645D01*
X519118Y-6674D01*
X519071Y-6697D01*
X519063Y-6700D01*
X519054Y-6707D01*
X519006Y-6730D01*
X518998Y-6733D01*
X518989Y-6739D01*
X518942Y-6762D01*
X518892Y-6779D01*
X518866Y-6784D01*
X518845Y-6794D01*
X518837Y-6797D01*
X518828Y-6803D01*
X518781Y-6827D01*
X518731Y-6843D01*
X518704Y-6849D01*
X518684Y-6859D01*
X518634Y-6876D01*
X518583Y-6886D01*
X518563Y-6887D01*
X518555Y-6891D01*
X518505Y-6908D01*
X518454Y-6918D01*
X518401Y-6922D01*
X518397D01*
X518394Y-6923D01*
X518344Y-6940D01*
X518292Y-6950D01*
X518240Y-6954D01*
X518203D01*
X518200Y-6956D01*
X518150Y-6972D01*
X518099Y-6983D01*
X518047Y-6986D01*
X518014D01*
X517998Y-6985D01*
X517982Y-6986D01*
X517950D01*
X517934Y-6985D01*
X517917Y-6986D01*
X517692D01*
X517639Y-6983D01*
X517588Y-6972D01*
X517538Y-6956D01*
X517535Y-6954D01*
X517466D01*
X517414Y-6950D01*
X517362Y-6940D01*
X517312Y-6923D01*
X517309Y-6922D01*
X517305D01*
X517252Y-6918D01*
X517201Y-6908D01*
X517151Y-6891D01*
X517131Y-6881D01*
X517104Y-6876D01*
X517054Y-6859D01*
X517034Y-6849D01*
X517007Y-6843D01*
X516958Y-6827D01*
X516937Y-6816D01*
X516910Y-6811D01*
X516861Y-6794D01*
X516814Y-6771D01*
X516804Y-6765D01*
X516796Y-6762D01*
X516749Y-6739D01*
X516740Y-6733D01*
X516732Y-6730D01*
X516685Y-6707D01*
X516675Y-6700D01*
X516667Y-6697D01*
X516620Y-6674D01*
X516611Y-6668D01*
X516603Y-6665D01*
X516556Y-6642D01*
X516512Y-6613D01*
X516488Y-6592D01*
X516459Y-6577D01*
X516415Y-6548D01*
X516391Y-6527D01*
X516362Y-6513D01*
X516319Y-6484D01*
X516279Y-6449D01*
X516264Y-6432D01*
X516247Y-6417D01*
X516232Y-6400D01*
X516230Y-6398D01*
X516201Y-6384D01*
X516157Y-6355D01*
X516118Y-6320D01*
X516103Y-6303D01*
X516085Y-6288D01*
X516070Y-6271D01*
X516053Y-6256D01*
X516038Y-6239D01*
X516021Y-6224D01*
X516006Y-6206D01*
X515989Y-6191D01*
X515974Y-6174D01*
X515956Y-6159D01*
X515922Y-6120D01*
X515893Y-6076D01*
X515884Y-6059D01*
X515878Y-6047D01*
X515877Y-6045D01*
X515860Y-6030D01*
X515845Y-6013D01*
X515827Y-5998D01*
X515793Y-5958D01*
X515764Y-5915D01*
X515749Y-5885D01*
X515728Y-5861D01*
X515699Y-5818D01*
X515676Y-5771D01*
X515673Y-5763D01*
X515667Y-5753D01*
X515652Y-5724D01*
X515631Y-5700D01*
X515602Y-5657D01*
X515579Y-5610D01*
X515577Y-5601D01*
X515570Y-5592D01*
X515547Y-5545D01*
X515544Y-5537D01*
X515538Y-5528D01*
X515515Y-5480D01*
X515498Y-5431D01*
X515492Y-5404D01*
X515482Y-5384D01*
X515480Y-5376D01*
X515473Y-5366D01*
X515450Y-5319D01*
X515433Y-5269D01*
X515428Y-5243D01*
X515418Y-5222D01*
X515401Y-5173D01*
X515391Y-5121D01*
X515389Y-5101D01*
X515386Y-5093D01*
X515369Y-5044D01*
X515358Y-4992D01*
X515355Y-4940D01*
Y-4936D01*
X515353Y-4932D01*
X515337Y-4882D01*
X515326Y-4831D01*
X515323Y-4779D01*
Y-4746D01*
Y-4714D01*
Y-4682D01*
Y-4650D01*
Y-4617D01*
Y-4585D01*
Y-4553D01*
Y-4521D01*
Y-4488D01*
Y-4456D01*
Y-4424D01*
Y-4391D01*
Y-4359D01*
Y-4327D01*
Y-4295D01*
Y-4262D01*
Y-4230D01*
Y-4198D01*
Y-4166D01*
X515326Y-4113D01*
X515337Y-4062D01*
X515353Y-4012D01*
X515355Y-4009D01*
Y-4004D01*
X515358Y-3952D01*
X515369Y-3901D01*
X515386Y-3851D01*
X515389Y-3843D01*
X515391Y-3823D01*
X515401Y-3771D01*
X515418Y-3722D01*
X515428Y-3701D01*
X515433Y-3675D01*
X515450Y-3625D01*
X515460Y-3605D01*
X515465Y-3578D01*
X515482Y-3528D01*
X515506Y-3481D01*
X515509Y-3476D01*
X515512Y-3472D01*
X515515Y-3464D01*
X515538Y-3417D01*
X515544Y-3407D01*
X515547Y-3399D01*
X515570Y-3352D01*
X515576Y-3343D01*
X515579Y-3335D01*
X515602Y-3288D01*
X515604Y-3286D01*
X515609Y-3278D01*
X515611Y-3270D01*
X515635Y-3223D01*
X515635Y-3222D01*
X515641Y-3214D01*
X515644Y-3206D01*
X515667Y-3159D01*
X515696Y-3115D01*
X515717Y-3091D01*
X515731Y-3062D01*
X515761Y-3018D01*
X515795Y-2979D01*
X515812Y-2964D01*
X515812Y-2964D01*
X515814Y-2962D01*
X515828Y-2933D01*
X515857Y-2889D01*
X515892Y-2850D01*
X515909Y-2835D01*
X515924Y-2818D01*
X515941Y-2802D01*
X515956Y-2785D01*
X515974Y-2770D01*
X515989Y-2753D01*
X516006Y-2738D01*
X516021Y-2721D01*
X516038Y-2706D01*
X516053Y-2688D01*
X516070Y-2673D01*
X516085Y-2656D01*
X516103Y-2641D01*
X516118Y-2624D01*
X516135Y-2609D01*
X516150Y-2592D01*
X516167Y-2577D01*
X516182Y-2560D01*
X516199Y-2544D01*
X516215Y-2527D01*
X516254Y-2493D01*
X516297Y-2464D01*
X516327Y-2449D01*
X516351Y-2428D01*
X516394Y-2399D01*
X516424Y-2385D01*
X516447Y-2364D01*
X516491Y-2334D01*
X516520Y-2320D01*
X516544Y-2299D01*
X516588Y-2270D01*
X516635Y-2247D01*
X516643Y-2244D01*
X516652Y-2238D01*
X516699Y-2214D01*
X516707Y-2212D01*
X516717Y-2205D01*
X516764Y-2182D01*
X516772Y-2180D01*
X516782Y-2173D01*
X516828Y-2150D01*
X516878Y-2133D01*
X516905Y-2128D01*
X516925Y-2118D01*
X516975Y-2101D01*
X517001Y-2096D01*
X517022Y-2085D01*
X517072Y-2069D01*
X517098Y-2063D01*
X517119Y-2053D01*
X517169Y-2036D01*
X517220Y-2026D01*
X517240Y-2025D01*
X517248Y-2021D01*
X517298Y-2004D01*
X517349Y-1994D01*
X517401Y-1990D01*
X517406D01*
X517409Y-1989D01*
X517459Y-1972D01*
X517510Y-1962D01*
X517563Y-1958D01*
X518143D01*
X518196Y-1962D01*
D02*
G37*
G36*
X501065Y14879D02*
X501116Y14869D01*
X501166Y14852D01*
X501169Y14850D01*
X501367D01*
X501419Y14847D01*
X501471Y14837D01*
X501521Y14820D01*
X501528Y14816D01*
X501549Y14815D01*
X501600Y14804D01*
X501650Y14787D01*
X501657Y14784D01*
X501678Y14782D01*
X501729Y14772D01*
X501779Y14755D01*
X501799Y14745D01*
X501826Y14740D01*
X501875Y14723D01*
X501896Y14713D01*
X501923Y14708D01*
X501972Y14691D01*
X502019Y14668D01*
X502029Y14661D01*
X502037Y14658D01*
X502084Y14635D01*
X502093Y14629D01*
X502101Y14626D01*
X502148Y14603D01*
X502158Y14597D01*
X502166Y14594D01*
X502213Y14571D01*
X502222Y14564D01*
X502230Y14562D01*
X502277Y14538D01*
X502287Y14532D01*
X502295Y14529D01*
X502342Y14506D01*
X502386Y14477D01*
X502409Y14456D01*
X502439Y14442D01*
X502482Y14412D01*
X502522Y14378D01*
X502537Y14361D01*
X502538Y14359D01*
X502568Y14345D01*
X502611Y14316D01*
X502651Y14281D01*
X502666Y14264D01*
X502675Y14256D01*
X502683Y14249D01*
X502698Y14232D01*
X502715Y14217D01*
X502730Y14199D01*
X502740Y14191D01*
X502747Y14184D01*
X502763Y14167D01*
X502780Y14152D01*
X502795Y14135D01*
X502812Y14120D01*
X502827Y14103D01*
X502842Y14090D01*
X502844Y14088D01*
X502859Y14070D01*
X502869Y14062D01*
X502877Y14055D01*
X502892Y14038D01*
X502909Y14023D01*
X502924Y14006D01*
X502941Y13991D01*
X502956Y13974D01*
X502973Y13959D01*
X503008Y13919D01*
X503037Y13876D01*
X503052Y13846D01*
X503053Y13845D01*
X503070Y13829D01*
X503105Y13790D01*
X503134Y13747D01*
X503157Y13700D01*
X503160Y13691D01*
X503166Y13682D01*
X503181Y13653D01*
X503189Y13643D01*
X503201Y13629D01*
X503231Y13585D01*
X503254Y13538D01*
X503257Y13530D01*
X503263Y13521D01*
X503263Y13521D01*
X503286Y13474D01*
X503289Y13466D01*
X503295Y13456D01*
X503295Y13456D01*
X503318Y13409D01*
X503321Y13401D01*
X503327Y13392D01*
X503351Y13345D01*
X503368Y13295D01*
X503373Y13268D01*
X503383Y13248D01*
X503400Y13198D01*
X503405Y13171D01*
X503415Y13151D01*
X503432Y13101D01*
X503437Y13075D01*
X503447Y13054D01*
X503464Y13005D01*
X503475Y12953D01*
X503476Y12933D01*
X503480Y12925D01*
X503497Y12876D01*
X503507Y12824D01*
X503510Y12772D01*
Y12740D01*
Y12735D01*
X503512Y12732D01*
X503529Y12682D01*
X503539Y12630D01*
X503543Y12578D01*
Y12546D01*
Y12514D01*
Y12481D01*
Y12449D01*
Y12417D01*
Y12385D01*
Y12352D01*
Y12320D01*
Y12288D01*
Y12256D01*
Y12223D01*
X503541Y12207D01*
X503543Y12191D01*
Y12159D01*
X503539Y12106D01*
X503529Y12055D01*
X503512Y12005D01*
X503510Y12002D01*
Y11998D01*
Y11965D01*
Y11933D01*
X503507Y11881D01*
X503497Y11829D01*
X503480Y11780D01*
X503476Y11772D01*
X503475Y11752D01*
X503464Y11700D01*
X503447Y11650D01*
X503437Y11630D01*
X503432Y11603D01*
X503415Y11554D01*
X503405Y11533D01*
X503400Y11507D01*
X503383Y11457D01*
X503373Y11436D01*
X503368Y11410D01*
X503351Y11360D01*
X503327Y11313D01*
X503321Y11304D01*
X503318Y11296D01*
X503295Y11249D01*
X503289Y11239D01*
X503286Y11231D01*
X503263Y11184D01*
X503257Y11175D01*
X503254Y11167D01*
X503231Y11120D01*
X503201Y11076D01*
X503181Y11052D01*
X503166Y11023D01*
X503137Y10979D01*
X503116Y10955D01*
X503102Y10926D01*
X503073Y10882D01*
X503038Y10843D01*
X503021Y10828D01*
X503019Y10826D01*
X503005Y10797D01*
X502976Y10753D01*
X502941Y10714D01*
X502924Y10699D01*
X502916Y10690D01*
X502909Y10682D01*
X502892Y10667D01*
X502879Y10653D01*
X502877Y10649D01*
X502859Y10634D01*
X502844Y10617D01*
X502827Y10602D01*
X502812Y10585D01*
X502795Y10570D01*
X502780Y10553D01*
X502764Y10539D01*
X502763Y10538D01*
X502747Y10520D01*
X502730Y10505D01*
X502715Y10488D01*
X502698Y10473D01*
X502683Y10456D01*
X502644Y10421D01*
X502600Y10392D01*
X502571Y10378D01*
X502569Y10376D01*
X502564Y10370D01*
X502554Y10359D01*
X502515Y10324D01*
X502471Y10295D01*
X502442Y10281D01*
X502418Y10260D01*
X502374Y10231D01*
X502345Y10216D01*
X502321Y10195D01*
X502277Y10166D01*
X502230Y10143D01*
X502222Y10140D01*
X502213Y10134D01*
X502166Y10111D01*
X502158Y10108D01*
X502148Y10102D01*
X502101Y10079D01*
X502093Y10076D01*
X502084Y10069D01*
X502037Y10046D01*
X501987Y10029D01*
X501961Y10024D01*
X501940Y10014D01*
X501932Y10011D01*
X501923Y10005D01*
X501875Y9982D01*
X501826Y9965D01*
X501774Y9955D01*
X501754Y9953D01*
X501746Y9950D01*
X501697Y9933D01*
X501670Y9927D01*
X501650Y9917D01*
X501600Y9900D01*
X501549Y9890D01*
X501496Y9887D01*
X501460D01*
X501456Y9885D01*
X501406Y9868D01*
X501355Y9858D01*
X501303Y9854D01*
X496588D01*
X496585Y9853D01*
X496535Y9836D01*
X496483Y9826D01*
X496431Y9822D01*
X496330D01*
X496326Y9821D01*
X496277Y9804D01*
X496225Y9793D01*
X496205Y9792D01*
X496197Y9788D01*
X496148Y9771D01*
X496096Y9761D01*
X496076Y9760D01*
X496068Y9756D01*
X496060Y9753D01*
X496051Y9747D01*
X496004Y9724D01*
X495954Y9707D01*
X495928Y9702D01*
X495907Y9691D01*
X495899Y9689D01*
X495890Y9682D01*
X495843Y9659D01*
X495834Y9657D01*
X495825Y9650D01*
X495778Y9627D01*
X495770Y9624D01*
X495760Y9618D01*
X495731Y9603D01*
X495723Y9596D01*
X495707Y9583D01*
X495664Y9553D01*
X495617Y9530D01*
X495609Y9527D01*
X495599Y9521D01*
X495570Y9507D01*
X495568Y9505D01*
X495553Y9488D01*
X495536Y9473D01*
X495521Y9456D01*
X495481Y9421D01*
X495438Y9392D01*
X495408Y9378D01*
X495407Y9376D01*
X495392Y9359D01*
X495375Y9344D01*
X495360Y9327D01*
X495342Y9312D01*
X495327Y9294D01*
X495310Y9279D01*
X495309Y9278D01*
X495294Y9248D01*
X495265Y9205D01*
X495230Y9165D01*
X495213Y9150D01*
X495212Y9149D01*
X495197Y9119D01*
X495168Y9076D01*
X495147Y9052D01*
X495133Y9023D01*
X495104Y8979D01*
X495083Y8955D01*
X495068Y8926D01*
X495062Y8916D01*
X495059Y8908D01*
X495036Y8861D01*
X495030Y8852D01*
X495027Y8844D01*
X495017Y8823D01*
X495012Y8797D01*
X494995Y8747D01*
X494972Y8700D01*
X494965Y8690D01*
X494963Y8682D01*
X494952Y8662D01*
X494947Y8635D01*
X494930Y8586D01*
X494926Y8578D01*
X494925Y8558D01*
X494915Y8506D01*
X494898Y8457D01*
X494896Y8453D01*
Y8449D01*
Y8416D01*
X494893Y8364D01*
X494883Y8313D01*
X494866Y8263D01*
X494864Y8259D01*
Y8255D01*
Y8223D01*
Y8191D01*
Y8158D01*
Y8126D01*
Y8094D01*
Y8062D01*
Y8057D01*
X494866Y8054D01*
X494883Y8004D01*
X494893Y7953D01*
X494896Y7900D01*
Y7868D01*
Y7864D01*
X494898Y7860D01*
X494915Y7810D01*
X494925Y7759D01*
X494926Y7739D01*
X494930Y7731D01*
X494947Y7681D01*
X494952Y7655D01*
X494963Y7634D01*
X494979Y7585D01*
X494985Y7558D01*
X494995Y7537D01*
X494998Y7530D01*
X495004Y7520D01*
X495027Y7473D01*
X495030Y7465D01*
X495036Y7456D01*
X495059Y7408D01*
X495062Y7401D01*
X495068Y7391D01*
X495092Y7344D01*
X495094Y7336D01*
X495101Y7326D01*
X495115Y7297D01*
X495136Y7273D01*
X495165Y7230D01*
X495180Y7200D01*
X495201Y7176D01*
X495230Y7133D01*
X495244Y7103D01*
X495246Y7102D01*
X495263Y7087D01*
X495278Y7070D01*
X495295Y7055D01*
X495310Y7037D01*
X495310Y7037D01*
X495327Y7022D01*
X495342Y7005D01*
X495360Y6990D01*
X495375Y6973D01*
X495392Y6958D01*
X495407Y6941D01*
X495424Y6926D01*
X495439Y6908D01*
X495456Y6893D01*
X495471Y6876D01*
X495489Y6861D01*
X495504Y6844D01*
X495505Y6842D01*
X495535Y6828D01*
X495578Y6799D01*
X495602Y6778D01*
X495632Y6763D01*
X495675Y6734D01*
X495699Y6713D01*
X495728Y6699D01*
X495738Y6692D01*
X495746Y6690D01*
X495793Y6667D01*
X495802Y6660D01*
X495810Y6657D01*
X495857Y6634D01*
X495867Y6628D01*
X495875Y6625D01*
X495922Y6602D01*
X495931Y6596D01*
X495939Y6593D01*
X495960Y6583D01*
X495986Y6578D01*
X496036Y6561D01*
X496057Y6551D01*
X496083Y6545D01*
X496133Y6528D01*
X496141Y6525D01*
X496161Y6523D01*
X496212Y6513D01*
X496262Y6496D01*
X496266Y6494D01*
X496270D01*
X496322Y6491D01*
X496374Y6481D01*
X496423Y6464D01*
X496427Y6462D01*
X521789D01*
X521805Y6461D01*
X521821Y6462D01*
X521853D01*
X521906Y6459D01*
X521957Y6448D01*
X522007Y6432D01*
X522010Y6430D01*
X522079D01*
X522132Y6426D01*
X522183Y6416D01*
X522233Y6399D01*
X522240Y6396D01*
X522261Y6394D01*
X522312Y6384D01*
X522362Y6367D01*
X522382Y6357D01*
X522409Y6352D01*
X522459Y6335D01*
X522479Y6325D01*
X522506Y6319D01*
X522555Y6303D01*
X522576Y6293D01*
X522602Y6287D01*
X522652Y6270D01*
X522699Y6247D01*
X522709Y6241D01*
X522717Y6238D01*
X522764Y6215D01*
X522773Y6209D01*
X522781Y6206D01*
X522828Y6183D01*
X522838Y6176D01*
X522846Y6174D01*
X522893Y6150D01*
X522902Y6144D01*
X522910Y6141D01*
X522957Y6118D01*
X523001Y6089D01*
X523025Y6068D01*
X523054Y6054D01*
X523098Y6024D01*
X523121Y6004D01*
X523151Y5989D01*
X523194Y5960D01*
X523234Y5925D01*
X523249Y5908D01*
X523266Y5893D01*
X523281Y5876D01*
X523283Y5875D01*
X523296Y5868D01*
X523312Y5860D01*
X523356Y5831D01*
X523395Y5796D01*
X523410Y5779D01*
X523427Y5764D01*
X523442Y5747D01*
X523460Y5732D01*
X523475Y5715D01*
X523492Y5700D01*
X523507Y5682D01*
X523524Y5667D01*
X523539Y5650D01*
X523556Y5635D01*
X523591Y5596D01*
X523620Y5552D01*
X523635Y5523D01*
X523636Y5521D01*
X523651Y5508D01*
X523653Y5506D01*
X523668Y5489D01*
X523685Y5474D01*
X523720Y5434D01*
X523749Y5391D01*
X523764Y5361D01*
X523784Y5337D01*
X523814Y5294D01*
X523828Y5265D01*
X523849Y5241D01*
X523878Y5197D01*
X523901Y5150D01*
X523904Y5142D01*
X523911Y5133D01*
X523934Y5086D01*
X523936Y5077D01*
X523943Y5068D01*
X523966Y5021D01*
X523969Y5013D01*
X523975Y5004D01*
X523998Y4956D01*
X524015Y4907D01*
X524020Y4880D01*
X524026Y4868D01*
X524030Y4860D01*
X524033Y4852D01*
X524040Y4842D01*
X524063Y4795D01*
X524080Y4746D01*
X524085Y4719D01*
X524095Y4698D01*
X524112Y4649D01*
X524122Y4597D01*
X524123Y4577D01*
X524127Y4569D01*
X524144Y4520D01*
X524154Y4468D01*
X524158Y4416D01*
Y4412D01*
X524159Y4408D01*
X524176Y4358D01*
X524187Y4307D01*
X524190Y4255D01*
Y4222D01*
Y4190D01*
Y4158D01*
Y4126D01*
Y4093D01*
Y4061D01*
Y4029D01*
Y3997D01*
Y3964D01*
Y3932D01*
Y3900D01*
Y3867D01*
Y3835D01*
Y3803D01*
Y3771D01*
Y3739D01*
Y3706D01*
Y3674D01*
Y3642D01*
X524187Y3589D01*
X524176Y3538D01*
X524159Y3488D01*
X524158Y3485D01*
Y3480D01*
X524154Y3428D01*
X524144Y3377D01*
X524127Y3327D01*
X524123Y3319D01*
X524122Y3299D01*
X524112Y3248D01*
X524095Y3198D01*
X524085Y3177D01*
X524080Y3151D01*
X524063Y3101D01*
X524053Y3081D01*
X524047Y3054D01*
X524030Y3004D01*
X524007Y2957D01*
X524001Y2948D01*
X523998Y2940D01*
X523975Y2893D01*
X523969Y2883D01*
X523966Y2875D01*
X523943Y2828D01*
X523936Y2819D01*
X523934Y2811D01*
X523911Y2764D01*
X523904Y2754D01*
X523901Y2746D01*
X523878Y2699D01*
X523872Y2690D01*
X523869Y2682D01*
X523846Y2635D01*
X523817Y2591D01*
X523796Y2567D01*
X523781Y2538D01*
X523752Y2494D01*
X523718Y2455D01*
X523707Y2445D01*
X523701Y2440D01*
X523685Y2423D01*
X523668Y2408D01*
X523667Y2406D01*
X523652Y2377D01*
X523623Y2333D01*
X523589Y2294D01*
X523571Y2279D01*
X523556Y2261D01*
X523539Y2246D01*
X523524Y2229D01*
X523507Y2214D01*
X523492Y2197D01*
X523475Y2182D01*
X523460Y2165D01*
X523442Y2149D01*
X523427Y2132D01*
X523410Y2117D01*
X523395Y2100D01*
X523378Y2085D01*
X523363Y2068D01*
X523346Y2053D01*
X523331Y2035D01*
X523291Y2001D01*
X523247Y1972D01*
X523218Y1957D01*
X523217Y1956D01*
X523202Y1939D01*
X523162Y1904D01*
X523118Y1875D01*
X523089Y1861D01*
X523065Y1840D01*
X523022Y1811D01*
X522975Y1787D01*
X522967Y1785D01*
X522957Y1778D01*
X522928Y1764D01*
X522904Y1743D01*
X522860Y1714D01*
X522813Y1691D01*
X522764Y1674D01*
X522737Y1668D01*
X522717Y1658D01*
X522709Y1656D01*
X522699Y1649D01*
X522652Y1626D01*
X522644Y1623D01*
X522635Y1617D01*
X522587Y1594D01*
X522538Y1577D01*
X522511Y1572D01*
X522491Y1562D01*
X522441Y1545D01*
X522414Y1539D01*
X522394Y1529D01*
X522344Y1512D01*
X522293Y1502D01*
X522273Y1501D01*
X522265Y1497D01*
X522215Y1480D01*
X522164Y1470D01*
X522112Y1467D01*
X522075D01*
X522071Y1465D01*
X522022Y1448D01*
X521970Y1438D01*
X521918Y1434D01*
X505331D01*
X505328Y1432D01*
X505278Y1416D01*
X505226Y1405D01*
X505174Y1402D01*
X505137D01*
X505134Y1400D01*
X505084Y1383D01*
X505033Y1373D01*
X505013Y1372D01*
X505005Y1368D01*
X504955Y1351D01*
X504904Y1341D01*
X504884Y1340D01*
X504876Y1336D01*
X504868Y1333D01*
X504858Y1327D01*
X504811Y1303D01*
X504762Y1287D01*
X504735Y1281D01*
X504714Y1271D01*
X504706Y1268D01*
X504697Y1262D01*
X504650Y1239D01*
X504642Y1236D01*
X504633Y1230D01*
X504586Y1207D01*
X504577Y1204D01*
X504568Y1197D01*
X504539Y1183D01*
X504515Y1162D01*
X504471Y1133D01*
X504442Y1119D01*
X504440Y1117D01*
X504425Y1100D01*
X504386Y1065D01*
X504342Y1036D01*
X504313Y1022D01*
X504311Y1020D01*
X504296Y1003D01*
X504279Y988D01*
X504264Y971D01*
X504247Y956D01*
X504232Y939D01*
X504214Y924D01*
X504199Y906D01*
X504199Y906D01*
X504182Y891D01*
X504167Y874D01*
X504150Y859D01*
X504135Y842D01*
X504118Y827D01*
X504103Y810D01*
X504085Y795D01*
X504084Y793D01*
X504069Y764D01*
X504040Y720D01*
X504019Y696D01*
X504005Y667D01*
X503976Y623D01*
X503955Y599D01*
X503940Y570D01*
X503934Y561D01*
X503931Y552D01*
X503908Y505D01*
X503902Y496D01*
X503899Y488D01*
X503876Y441D01*
X503869Y431D01*
X503867Y423D01*
X503844Y376D01*
X503837Y367D01*
X503835Y359D01*
X503824Y338D01*
X503819Y312D01*
X503802Y262D01*
X503792Y242D01*
X503787Y215D01*
X503770Y165D01*
X503766Y158D01*
X503765Y137D01*
X503755Y86D01*
X503738Y36D01*
X503736Y33D01*
Y28D01*
Y-4D01*
X503733Y-56D01*
X503722Y-108D01*
X503706Y-157D01*
X503704Y-161D01*
Y-165D01*
Y-197D01*
Y-230D01*
Y-262D01*
Y-294D01*
Y-326D01*
Y-359D01*
Y-363D01*
X503706Y-367D01*
X503722Y-416D01*
X503733Y-468D01*
X503736Y-520D01*
Y-552D01*
Y-557D01*
X503738Y-560D01*
X503755Y-610D01*
X503765Y-661D01*
X503766Y-681D01*
X503770Y-689D01*
X503787Y-739D01*
X503792Y-766D01*
X503802Y-786D01*
X503819Y-836D01*
X503824Y-862D01*
X503835Y-883D01*
X503837Y-891D01*
X503844Y-900D01*
X503867Y-947D01*
X503869Y-955D01*
X503876Y-965D01*
X503899Y-1012D01*
X503902Y-1020D01*
X503908Y-1029D01*
X503931Y-1076D01*
X503934Y-1084D01*
X503940Y-1094D01*
X503955Y-1123D01*
X503963Y-1133D01*
X503976Y-1147D01*
X504005Y-1191D01*
X504019Y-1220D01*
X504021Y-1222D01*
X504038Y-1237D01*
X504073Y-1276D01*
X504102Y-1320D01*
X504116Y-1349D01*
X504118Y-1351D01*
X504127Y-1359D01*
X504135Y-1366D01*
X504150Y-1383D01*
X504167Y-1398D01*
X504182Y-1415D01*
X504199Y-1430D01*
X504214Y-1448D01*
X504215Y-1448D01*
X504232Y-1463D01*
X504247Y-1480D01*
X504256Y-1488D01*
X504264Y-1495D01*
X504279Y-1512D01*
X504281Y-1514D01*
X504310Y-1528D01*
X504354Y-1557D01*
X504393Y-1592D01*
X504408Y-1609D01*
X504410Y-1610D01*
X504439Y-1625D01*
X504483Y-1654D01*
X504506Y-1675D01*
X504536Y-1689D01*
X504545Y-1696D01*
X504553Y-1698D01*
X504600Y-1722D01*
X504644Y-1751D01*
X504668Y-1771D01*
X504670Y-1773D01*
X504697Y-1778D01*
X504747Y-1795D01*
X504794Y-1818D01*
X504803Y-1825D01*
X504811Y-1827D01*
X504832Y-1837D01*
X504858Y-1843D01*
X504908Y-1860D01*
X504929Y-1870D01*
X504955Y-1875D01*
X505005Y-1892D01*
X505013Y-1896D01*
X505033Y-1897D01*
X505084Y-1907D01*
X505134Y-1924D01*
X505137Y-1926D01*
X505206D01*
X505259Y-1929D01*
X505310Y-1939D01*
X505360Y-1956D01*
X505363Y-1958D01*
X511401D01*
X511453Y-1962D01*
X511504Y-1972D01*
X511554Y-1989D01*
X511557Y-1990D01*
X511562D01*
X511614Y-1994D01*
X511666Y-2004D01*
X511715Y-2021D01*
X511723Y-2025D01*
X511743Y-2026D01*
X511795Y-2036D01*
X511844Y-2053D01*
X511865Y-2063D01*
X511892Y-2069D01*
X511941Y-2085D01*
X511962Y-2096D01*
X511988Y-2101D01*
X512038Y-2118D01*
X512058Y-2128D01*
X512085Y-2133D01*
X512135Y-2150D01*
X512182Y-2173D01*
X512191Y-2180D01*
X512199Y-2182D01*
X512246Y-2205D01*
X512256Y-2212D01*
X512264Y-2214D01*
X512311Y-2238D01*
X512320Y-2244D01*
X512328Y-2247D01*
X512375Y-2270D01*
X512385Y-2276D01*
X512393Y-2279D01*
X512440Y-2302D01*
X512483Y-2331D01*
X512507Y-2352D01*
X512537Y-2367D01*
X512580Y-2396D01*
X512620Y-2430D01*
X512635Y-2448D01*
X512636Y-2449D01*
X512666Y-2464D01*
X512709Y-2493D01*
X512749Y-2527D01*
X512764Y-2544D01*
X512781Y-2560D01*
X512796Y-2577D01*
X512813Y-2592D01*
X512828Y-2609D01*
X512846Y-2624D01*
X512860Y-2641D01*
X512878Y-2656D01*
X512893Y-2673D01*
X512910Y-2688D01*
X512925Y-2706D01*
X512942Y-2721D01*
X512957Y-2738D01*
X512975Y-2753D01*
X512990Y-2770D01*
X513007Y-2785D01*
X513022Y-2803D01*
X513039Y-2818D01*
X513054Y-2835D01*
X513071Y-2850D01*
X513086Y-2867D01*
X513104Y-2882D01*
X513138Y-2922D01*
X513167Y-2965D01*
X513182Y-2994D01*
X513183Y-2996D01*
X513200Y-3011D01*
X513235Y-3051D01*
X513264Y-3094D01*
X513287Y-3141D01*
X513290Y-3149D01*
X513296Y-3159D01*
X513311Y-3188D01*
X513332Y-3212D01*
X513361Y-3255D01*
X513384Y-3303D01*
X513387Y-3311D01*
X513393Y-3320D01*
X513393Y-3320D01*
X513416Y-3367D01*
X513419Y-3375D01*
X513424Y-3382D01*
X513425Y-3384D01*
X513449Y-3432D01*
X513465Y-3481D01*
X513471Y-3508D01*
X513481Y-3528D01*
X513484Y-3536D01*
X513490Y-3546D01*
X513513Y-3593D01*
X513530Y-3642D01*
X513535Y-3669D01*
X513545Y-3690D01*
X513562Y-3739D01*
X513572Y-3791D01*
X513574Y-3811D01*
X513578Y-3819D01*
X513594Y-3868D01*
X513605Y-3920D01*
X513608Y-3972D01*
Y-3976D01*
X513610Y-3980D01*
X513627Y-4030D01*
X513637Y-4081D01*
X513640Y-4133D01*
Y-4166D01*
Y-4198D01*
Y-4230D01*
Y-4262D01*
Y-4295D01*
Y-4327D01*
Y-4359D01*
Y-4391D01*
Y-4424D01*
Y-4456D01*
Y-4488D01*
Y-4521D01*
Y-4553D01*
Y-4585D01*
Y-4617D01*
Y-4650D01*
Y-4682D01*
Y-4714D01*
Y-4746D01*
Y-4779D01*
Y-4811D01*
X513637Y-4863D01*
X513627Y-4915D01*
X513610Y-4964D01*
X513608Y-4968D01*
Y-4972D01*
X513605Y-5024D01*
X513594Y-5076D01*
X513578Y-5126D01*
X513567Y-5146D01*
X513562Y-5173D01*
X513545Y-5222D01*
X513535Y-5243D01*
X513535Y-5246D01*
X513530Y-5269D01*
X513513Y-5319D01*
X513503Y-5340D01*
X513498Y-5366D01*
X513481Y-5416D01*
X513458Y-5463D01*
X513451Y-5472D01*
X513449Y-5480D01*
X513449Y-5480D01*
X513425Y-5528D01*
X513419Y-5537D01*
X513416Y-5545D01*
X513393Y-5592D01*
X513387Y-5601D01*
X513384Y-5610D01*
X513361Y-5657D01*
X513354Y-5666D01*
X513352Y-5674D01*
X513329Y-5721D01*
X513322Y-5731D01*
X513319Y-5739D01*
X513296Y-5786D01*
X513267Y-5829D01*
X513246Y-5853D01*
X513232Y-5882D01*
X513203Y-5926D01*
X513168Y-5965D01*
X513151Y-5980D01*
X513136Y-5998D01*
X513119Y-6013D01*
X513117Y-6014D01*
X513103Y-6044D01*
X513074Y-6087D01*
X513039Y-6127D01*
X513022Y-6142D01*
X513007Y-6159D01*
X512990Y-6174D01*
X512975Y-6191D01*
X512957Y-6206D01*
X512942Y-6224D01*
X512925Y-6239D01*
X512914Y-6251D01*
X512910Y-6256D01*
X512893Y-6271D01*
X512878Y-6288D01*
X512860Y-6303D01*
X512857Y-6307D01*
X512846Y-6320D01*
X512828Y-6335D01*
X512813Y-6352D01*
X512774Y-6387D01*
X512730Y-6416D01*
X512701Y-6431D01*
X512699Y-6432D01*
X512692Y-6441D01*
X512684Y-6449D01*
X512645Y-6484D01*
X512601Y-6513D01*
X512572Y-6527D01*
X512548Y-6548D01*
X512504Y-6577D01*
X512475Y-6592D01*
X512451Y-6613D01*
X512408Y-6642D01*
X512360Y-6665D01*
X512353Y-6668D01*
X512343Y-6674D01*
X512296Y-6697D01*
X512288Y-6700D01*
X512279Y-6707D01*
X512231Y-6730D01*
X512223Y-6733D01*
X512215Y-6739D01*
X512214Y-6739D01*
X512167Y-6762D01*
X512159Y-6765D01*
X512153Y-6769D01*
X512149Y-6771D01*
X512103Y-6794D01*
X512053Y-6811D01*
X512026Y-6816D01*
X512006Y-6827D01*
X511956Y-6843D01*
X511929Y-6849D01*
X511909Y-6859D01*
X511859Y-6876D01*
X511833Y-6881D01*
X511812Y-6891D01*
X511762Y-6908D01*
X511711Y-6918D01*
X511659Y-6922D01*
X511654D01*
X511651Y-6923D01*
X511601Y-6940D01*
X511550Y-6950D01*
X511497Y-6954D01*
X511428D01*
X511425Y-6956D01*
X511375Y-6972D01*
X511324Y-6983D01*
X511272Y-6986D01*
X511207D01*
X511191Y-6985D01*
X511175Y-6986D01*
X501496D01*
X501480Y-6985D01*
X501464Y-6986D01*
X501298D01*
X501295Y-6988D01*
X501245Y-7005D01*
X501194Y-7015D01*
X501141Y-7018D01*
X501137D01*
X501133Y-7020D01*
X501084Y-7037D01*
X501032Y-7047D01*
X501012Y-7049D01*
X501004Y-7052D01*
X500955Y-7069D01*
X500928Y-7075D01*
X500908Y-7085D01*
X500900Y-7087D01*
X500890Y-7094D01*
X500843Y-7117D01*
X500793Y-7134D01*
X500767Y-7139D01*
X500746Y-7149D01*
X500738Y-7152D01*
X500729Y-7158D01*
X500700Y-7173D01*
X500676Y-7194D01*
X500632Y-7223D01*
X500585Y-7246D01*
X500577Y-7249D01*
X500567Y-7255D01*
X500538Y-7270D01*
X500530Y-7277D01*
X500514Y-7290D01*
X500471Y-7320D01*
X500441Y-7334D01*
X500440Y-7335D01*
X500425Y-7353D01*
X500408Y-7368D01*
X500392Y-7385D01*
X500353Y-7419D01*
X500309Y-7449D01*
X500280Y-7463D01*
X500278Y-7465D01*
X500263Y-7482D01*
X500246Y-7497D01*
X500245Y-7498D01*
X500230Y-7528D01*
X500201Y-7571D01*
X500167Y-7611D01*
X500149Y-7626D01*
X500134Y-7643D01*
X500117Y-7658D01*
X500116Y-7660D01*
X500108Y-7675D01*
X500101Y-7689D01*
X500072Y-7733D01*
X500051Y-7756D01*
X500037Y-7786D01*
X500008Y-7829D01*
X499987Y-7853D01*
X499972Y-7883D01*
X499966Y-7892D01*
X499963Y-7900D01*
X499940Y-7947D01*
X499934Y-7957D01*
X499931Y-7965D01*
X499908Y-8012D01*
X499901Y-8021D01*
X499899Y-8029D01*
X499889Y-8050D01*
X499883Y-8076D01*
X499866Y-8126D01*
X499856Y-8146D01*
X499852Y-8166D01*
X499851Y-8173D01*
X499834Y-8223D01*
X499824Y-8243D01*
X499819Y-8270D01*
X499802Y-8320D01*
X499800Y-8323D01*
Y-8327D01*
X499797Y-8380D01*
X499786Y-8431D01*
X499770Y-8481D01*
X499768Y-8484D01*
Y-8489D01*
Y-8521D01*
Y-8553D01*
Y-8585D01*
Y-8618D01*
Y-8650D01*
Y-8682D01*
Y-8715D01*
Y-8747D01*
Y-8779D01*
Y-8811D01*
Y-8844D01*
Y-8848D01*
X499770Y-8851D01*
X499786Y-8901D01*
X499797Y-8953D01*
X499800Y-9005D01*
Y-9009D01*
X499802Y-9013D01*
X499819Y-9063D01*
X499824Y-9089D01*
X499834Y-9110D01*
X499851Y-9159D01*
X499856Y-9186D01*
X499866Y-9206D01*
X499883Y-9256D01*
X499889Y-9283D01*
X499899Y-9303D01*
X499901Y-9311D01*
X499908Y-9321D01*
X499931Y-9368D01*
X499934Y-9376D01*
X499940Y-9385D01*
X499963Y-9432D01*
X499966Y-9440D01*
X499972Y-9450D01*
X499995Y-9497D01*
X499998Y-9505D01*
X500004Y-9514D01*
X500019Y-9544D01*
X500034Y-9560D01*
X500040Y-9567D01*
X500069Y-9611D01*
X500083Y-9640D01*
X500085Y-9642D01*
X500102Y-9657D01*
X500102Y-9657D01*
X500137Y-9697D01*
X500166Y-9740D01*
X500180Y-9769D01*
X500182Y-9771D01*
X500199Y-9786D01*
X500214Y-9803D01*
X500231Y-9818D01*
X500246Y-9836D01*
X500263Y-9851D01*
X500278Y-9868D01*
X500296Y-9883D01*
X500311Y-9900D01*
X500328Y-9915D01*
X500343Y-9932D01*
X500345Y-9934D01*
X500374Y-9948D01*
X500418Y-9977D01*
X500457Y-10012D01*
X500472Y-10029D01*
X500474Y-10030D01*
X500503Y-10045D01*
X500547Y-10074D01*
X500570Y-10095D01*
X500600Y-10110D01*
X500609Y-10116D01*
X500617Y-10119D01*
X500664Y-10142D01*
X500674Y-10148D01*
X500682Y-10151D01*
X500729Y-10174D01*
X500738Y-10180D01*
X500746Y-10183D01*
X500793Y-10206D01*
X500803Y-10213D01*
X500811Y-10215D01*
X500831Y-10226D01*
X500858Y-10231D01*
X500908Y-10248D01*
X500955Y-10271D01*
X500964Y-10277D01*
X500972Y-10280D01*
X500980Y-10284D01*
X501000Y-10285D01*
X501052Y-10295D01*
X501101Y-10312D01*
X501105Y-10314D01*
X501109D01*
X501161Y-10317D01*
X501213Y-10328D01*
X501263Y-10344D01*
X501266Y-10346D01*
X501399D01*
X501452Y-10350D01*
X501503Y-10360D01*
X501553Y-10377D01*
X501556Y-10379D01*
X508078D01*
X508130Y-10382D01*
X508181Y-10392D01*
X508231Y-10409D01*
X508235Y-10411D01*
X508239D01*
X508291Y-10414D01*
X508343Y-10424D01*
X508392Y-10441D01*
X508413Y-10451D01*
X508439Y-10457D01*
X508489Y-10474D01*
X508510Y-10484D01*
X508536Y-10489D01*
X508586Y-10506D01*
X508606Y-10516D01*
X508633Y-10521D01*
X508683Y-10538D01*
X508703Y-10548D01*
X508730Y-10553D01*
X508779Y-10570D01*
X508826Y-10593D01*
X508836Y-10600D01*
X508844Y-10603D01*
X508891Y-10626D01*
X508900Y-10632D01*
X508909Y-10635D01*
X508956Y-10658D01*
X508999Y-10687D01*
X509023Y-10708D01*
X509052Y-10723D01*
X509062Y-10729D01*
X509070Y-10732D01*
X509117Y-10755D01*
X509161Y-10784D01*
X509184Y-10805D01*
X509214Y-10819D01*
X509257Y-10848D01*
X509297Y-10883D01*
X509312Y-10900D01*
X509312Y-10901D01*
X509329Y-10915D01*
X509344Y-10932D01*
X509346Y-10934D01*
X509375Y-10948D01*
X509419Y-10977D01*
X509458Y-11012D01*
X509473Y-11029D01*
X509490Y-11044D01*
X509505Y-11062D01*
X509522Y-11077D01*
X509538Y-11094D01*
X509555Y-11109D01*
X509570Y-11126D01*
X509587Y-11141D01*
X509602Y-11158D01*
X509619Y-11173D01*
X509654Y-11213D01*
X509683Y-11256D01*
X509697Y-11286D01*
X509699Y-11287D01*
X509714Y-11301D01*
X509716Y-11302D01*
X509731Y-11320D01*
X509748Y-11335D01*
X509783Y-11374D01*
X509812Y-11418D01*
X509827Y-11447D01*
X509847Y-11471D01*
X509877Y-11514D01*
X509891Y-11544D01*
X509912Y-11568D01*
X509941Y-11611D01*
X509964Y-11658D01*
X509967Y-11666D01*
X509973Y-11676D01*
X509997Y-11723D01*
X509999Y-11731D01*
X510006Y-11740D01*
X510029Y-11787D01*
X510032Y-11795D01*
X510038Y-11805D01*
X510061Y-11852D01*
X510064Y-11860D01*
X510070Y-11869D01*
X510093Y-11916D01*
X510110Y-11966D01*
X510115Y-11993D01*
X510126Y-12013D01*
X510143Y-12063D01*
X510148Y-12089D01*
X510158Y-12110D01*
X510175Y-12160D01*
X510180Y-12186D01*
X510186Y-12199D01*
X510190Y-12207D01*
X510207Y-12256D01*
X510217Y-12308D01*
X510221Y-12360D01*
Y-12392D01*
Y-12397D01*
X510222Y-12400D01*
X510239Y-12450D01*
X510250Y-12501D01*
X510253Y-12554D01*
Y-12586D01*
Y-12618D01*
Y-12651D01*
Y-12683D01*
Y-12687D01*
X510255Y-12691D01*
X510272Y-12740D01*
X510282Y-12792D01*
X510285Y-12844D01*
Y-12876D01*
Y-12909D01*
X510282Y-12961D01*
X510272Y-13012D01*
X510255Y-13062D01*
X510253Y-13066D01*
Y-13070D01*
Y-13102D01*
Y-13134D01*
Y-13167D01*
Y-13199D01*
Y-13231D01*
X510250Y-13284D01*
X510239Y-13335D01*
X510222Y-13385D01*
X510221Y-13388D01*
Y-13393D01*
X510217Y-13445D01*
X510207Y-13496D01*
X510190Y-13546D01*
X510180Y-13566D01*
X510176Y-13586D01*
X510175Y-13593D01*
X510158Y-13643D01*
X510148Y-13663D01*
X510143Y-13690D01*
X510126Y-13739D01*
X510115Y-13760D01*
X510110Y-13787D01*
X510093Y-13836D01*
X510083Y-13857D01*
X510078Y-13883D01*
X510061Y-13933D01*
X510038Y-13980D01*
X510032Y-13990D01*
X510029Y-13998D01*
X510006Y-14045D01*
X509999Y-14054D01*
X509997Y-14062D01*
X509973Y-14109D01*
X509967Y-14119D01*
X509964Y-14127D01*
X509941Y-14174D01*
X509912Y-14217D01*
X509891Y-14241D01*
X509877Y-14270D01*
X509847Y-14314D01*
X509827Y-14338D01*
X509812Y-14367D01*
X509783Y-14411D01*
X509748Y-14450D01*
X509731Y-14465D01*
X509730Y-14467D01*
X509715Y-14496D01*
X509686Y-14540D01*
X509652Y-14579D01*
X509634Y-14594D01*
X509619Y-14612D01*
X509602Y-14627D01*
X509587Y-14644D01*
X509570Y-14659D01*
X509555Y-14676D01*
X509538Y-14691D01*
X509522Y-14708D01*
X509505Y-14723D01*
X509490Y-14741D01*
X509473Y-14756D01*
X509458Y-14773D01*
X509441Y-14788D01*
X509426Y-14805D01*
X509409Y-14820D01*
X509403Y-14826D01*
X509394Y-14837D01*
X509376Y-14852D01*
X509361Y-14870D01*
X509344Y-14885D01*
X509330Y-14901D01*
X509329Y-14902D01*
X509290Y-14936D01*
X509246Y-14966D01*
X509217Y-14980D01*
X509215Y-14981D01*
X509200Y-14999D01*
X509161Y-15033D01*
X509117Y-15062D01*
X509088Y-15077D01*
X509064Y-15098D01*
X509020Y-15127D01*
X508973Y-15150D01*
X508965Y-15153D01*
X508956Y-15159D01*
X508909Y-15182D01*
X508901Y-15185D01*
X508891Y-15191D01*
X508844Y-15215D01*
X508836Y-15217D01*
X508826Y-15224D01*
X508779Y-15247D01*
X508772Y-15250D01*
X508762Y-15256D01*
X508715Y-15279D01*
X508665Y-15296D01*
X508639Y-15301D01*
X508618Y-15311D01*
X508568Y-15328D01*
X508517Y-15338D01*
X508497Y-15340D01*
X508489Y-15344D01*
X508439Y-15361D01*
X508388Y-15371D01*
X508336Y-15374D01*
X485315D01*
Y-15393D01*
Y-15425D01*
Y-15457D01*
Y-15489D01*
Y-15522D01*
Y-15554D01*
Y-15586D01*
Y-15619D01*
Y-15651D01*
Y-15683D01*
Y-15715D01*
Y-15748D01*
Y-15780D01*
Y-15812D01*
Y-15844D01*
Y-15877D01*
Y-15909D01*
Y-15941D01*
Y-15973D01*
Y-16006D01*
Y-16038D01*
Y-16070D01*
Y-16103D01*
Y-16135D01*
Y-16167D01*
Y-16199D01*
Y-16232D01*
Y-16264D01*
Y-16296D01*
Y-16328D01*
Y-16361D01*
Y-16393D01*
Y-16425D01*
Y-16457D01*
Y-16490D01*
Y-16522D01*
Y-16554D01*
Y-16586D01*
Y-16619D01*
Y-16651D01*
Y-16683D01*
Y-16715D01*
Y-16748D01*
Y-16780D01*
Y-16812D01*
Y-16845D01*
Y-16877D01*
Y-16909D01*
Y-16941D01*
Y-16974D01*
Y-17006D01*
Y-17038D01*
Y-17070D01*
Y-17103D01*
Y-17135D01*
Y-17167D01*
Y-17199D01*
Y-17232D01*
Y-17264D01*
Y-17296D01*
Y-17328D01*
Y-17361D01*
Y-17393D01*
Y-17425D01*
Y-17458D01*
Y-17490D01*
Y-17522D01*
Y-17554D01*
Y-17586D01*
Y-17619D01*
Y-17651D01*
Y-17683D01*
Y-17716D01*
Y-17748D01*
Y-17780D01*
Y-17812D01*
Y-17845D01*
Y-17877D01*
Y-17909D01*
Y-17941D01*
Y-17974D01*
Y-18006D01*
Y-18038D01*
Y-18070D01*
Y-18103D01*
Y-18135D01*
Y-18167D01*
Y-18200D01*
Y-18232D01*
Y-18264D01*
Y-18296D01*
Y-18329D01*
Y-18361D01*
X485311Y-18413D01*
X485301Y-18465D01*
X485284Y-18514D01*
X485261Y-18561D01*
X485254Y-18571D01*
X485252Y-18579D01*
X485229Y-18626D01*
X485222Y-18635D01*
X485219Y-18643D01*
X485196Y-18690D01*
X485167Y-18734D01*
X485133Y-18773D01*
X485115Y-18788D01*
X485100Y-18806D01*
X485061Y-18840D01*
X485017Y-18869D01*
X484970Y-18892D01*
X484962Y-18895D01*
X484953Y-18902D01*
X484906Y-18925D01*
X484898Y-18927D01*
X484888Y-18934D01*
X484841Y-18957D01*
X484792Y-18974D01*
X484740Y-18984D01*
X484688Y-18988D01*
X478526D01*
X478474Y-18984D01*
X478422Y-18974D01*
X478372Y-18957D01*
X478352Y-18947D01*
X478325Y-18942D01*
X478276Y-18925D01*
X478229Y-18902D01*
X478185Y-18872D01*
X478146Y-18838D01*
X478139Y-18831D01*
X478130Y-18821D01*
X478113Y-18806D01*
X478098Y-18788D01*
X478081Y-18773D01*
X478066Y-18756D01*
X478049Y-18741D01*
X478014Y-18702D01*
X477998Y-18677D01*
X477971Y-18709D01*
X477953Y-18724D01*
X477938Y-18741D01*
X477921Y-18756D01*
X477906Y-18773D01*
X477889Y-18788D01*
X477874Y-18806D01*
X477856Y-18821D01*
X477841Y-18838D01*
X477802Y-18872D01*
X477758Y-18902D01*
X477711Y-18925D01*
X477662Y-18942D01*
X477635Y-18947D01*
X477615Y-18957D01*
X477565Y-18974D01*
X477514Y-18984D01*
X477461Y-18988D01*
X474299D01*
X474247Y-18984D01*
X474196Y-18974D01*
X474146Y-18957D01*
X474099Y-18934D01*
X474090Y-18927D01*
X474082Y-18925D01*
X474035Y-18902D01*
X474025Y-18895D01*
X474017Y-18892D01*
X473970Y-18869D01*
X473926Y-18840D01*
X473887Y-18806D01*
X473872Y-18788D01*
X473855Y-18773D01*
X473820Y-18734D01*
X473791Y-18690D01*
X473768Y-18643D01*
X473765Y-18635D01*
X473759Y-18626D01*
X473736Y-18579D01*
X473719Y-18529D01*
X473713Y-18503D01*
X473703Y-18482D01*
X473687Y-18432D01*
X473676Y-18381D01*
X473673Y-18329D01*
Y-18296D01*
Y-18264D01*
Y-18232D01*
Y-18200D01*
Y-18167D01*
Y-18135D01*
Y-18103D01*
Y-18070D01*
Y-18038D01*
Y-18006D01*
Y-17974D01*
Y-17941D01*
Y-17909D01*
Y-17877D01*
Y-17845D01*
Y-17812D01*
Y-17780D01*
Y-17748D01*
Y-17716D01*
Y-17683D01*
Y-17651D01*
Y-17619D01*
Y-17586D01*
Y-17554D01*
Y-17522D01*
Y-17490D01*
Y-17458D01*
Y-17425D01*
Y-17393D01*
Y-17361D01*
Y-17328D01*
Y-17296D01*
Y-17264D01*
Y-17232D01*
Y-17199D01*
Y-17167D01*
Y-17135D01*
Y-17103D01*
Y-17070D01*
Y-17038D01*
Y-17006D01*
Y-16974D01*
Y-16941D01*
Y-16909D01*
Y-16877D01*
Y-16845D01*
Y-16812D01*
Y-16780D01*
Y-16748D01*
Y-16715D01*
Y-16683D01*
Y-16651D01*
Y-16619D01*
Y-16586D01*
D01*
Y-16554D01*
Y-16522D01*
Y-16490D01*
Y-16457D01*
Y-16425D01*
Y-16393D01*
Y-16361D01*
Y-16328D01*
Y-16296D01*
Y-16264D01*
Y-16232D01*
Y-16199D01*
Y-16167D01*
Y-16135D01*
Y-16103D01*
Y-16070D01*
Y-16038D01*
Y-16006D01*
Y-15973D01*
Y-15941D01*
Y-15909D01*
Y-15877D01*
Y-15844D01*
Y-15812D01*
Y-15780D01*
Y-15748D01*
Y-15715D01*
X473674Y-15699D01*
X473673Y-15683D01*
Y-15651D01*
Y-15619D01*
Y-15586D01*
Y-15554D01*
Y-15550D01*
X473671Y-15546D01*
X473668Y-15538D01*
X473662Y-15529D01*
X473639Y-15482D01*
X473637Y-15477D01*
X473636Y-15474D01*
X473630Y-15464D01*
X473615Y-15435D01*
X473614Y-15433D01*
X473612Y-15432D01*
X473583Y-15417D01*
X473573Y-15411D01*
X473565Y-15408D01*
X473545Y-15398D01*
X473518Y-15393D01*
X473493Y-15384D01*
X473468Y-15393D01*
X473441Y-15398D01*
X473421Y-15408D01*
X473413Y-15411D01*
X473403Y-15417D01*
X473374Y-15432D01*
X473372Y-15433D01*
X473366Y-15440D01*
X473357Y-15450D01*
X473340Y-15465D01*
X473338Y-15467D01*
X473324Y-15496D01*
X473318Y-15506D01*
X473315Y-15514D01*
X473313Y-15517D01*
Y-15522D01*
Y-15554D01*
X473312Y-15570D01*
X473313Y-15586D01*
Y-15619D01*
Y-15651D01*
X473312Y-15667D01*
X473313Y-15683D01*
Y-15715D01*
Y-15748D01*
Y-15780D01*
Y-15812D01*
Y-15844D01*
Y-15877D01*
Y-15909D01*
Y-15941D01*
Y-15973D01*
Y-16006D01*
Y-16038D01*
Y-16070D01*
Y-16103D01*
Y-16135D01*
Y-16167D01*
Y-16199D01*
Y-16232D01*
Y-16264D01*
Y-16296D01*
Y-16328D01*
Y-16361D01*
Y-16393D01*
Y-16425D01*
Y-16457D01*
Y-16490D01*
Y-16522D01*
Y-16554D01*
Y-16586D01*
D01*
Y-16619D01*
Y-16651D01*
Y-16683D01*
Y-16715D01*
Y-16748D01*
Y-16780D01*
Y-16812D01*
Y-16845D01*
Y-16877D01*
Y-16909D01*
Y-16941D01*
Y-16974D01*
Y-17006D01*
Y-17038D01*
Y-17070D01*
X473310Y-17123D01*
X473300Y-17174D01*
X473283Y-17224D01*
X473279Y-17232D01*
X473278Y-17252D01*
X473267Y-17303D01*
X473250Y-17353D01*
X473227Y-17400D01*
X473198Y-17443D01*
X473164Y-17483D01*
X473146Y-17498D01*
X473131Y-17515D01*
X473114Y-17530D01*
X473114Y-17530D01*
X473099Y-17547D01*
X473082Y-17562D01*
X473067Y-17580D01*
X473049Y-17595D01*
X473034Y-17612D01*
X472995Y-17647D01*
X472951Y-17676D01*
X472904Y-17699D01*
X472855Y-17716D01*
X472828Y-17721D01*
X472808Y-17731D01*
X472758Y-17748D01*
X472707Y-17758D01*
X472654Y-17762D01*
X470718D01*
X470666Y-17758D01*
X470615Y-17748D01*
X470565Y-17731D01*
X470545Y-17721D01*
X470518Y-17716D01*
X470468Y-17699D01*
X470421Y-17676D01*
X470378Y-17647D01*
X470338Y-17612D01*
X470323Y-17595D01*
X470306Y-17580D01*
X470291Y-17562D01*
X470274Y-17547D01*
X470259Y-17530D01*
X470241Y-17515D01*
X470226Y-17498D01*
X470209Y-17483D01*
X470175Y-17443D01*
X470146Y-17400D01*
X470122Y-17353D01*
X470106Y-17303D01*
X470100Y-17277D01*
X470090Y-17256D01*
X470073Y-17206D01*
X470063Y-17155D01*
X470059Y-17103D01*
Y-17070D01*
Y-17038D01*
Y-17006D01*
Y-16974D01*
Y-16941D01*
Y-16909D01*
Y-16877D01*
Y-16845D01*
Y-16812D01*
Y-16780D01*
Y-16748D01*
Y-16715D01*
Y-16683D01*
Y-16651D01*
Y-16619D01*
Y-16586D01*
D01*
Y-16554D01*
Y-16522D01*
Y-16490D01*
Y-16457D01*
Y-16425D01*
Y-16393D01*
Y-16361D01*
Y-16328D01*
Y-16296D01*
Y-16264D01*
Y-16232D01*
Y-16199D01*
Y-16167D01*
Y-16135D01*
Y-16103D01*
Y-16070D01*
Y-16038D01*
Y-16006D01*
Y-15973D01*
Y-15941D01*
Y-15909D01*
Y-15877D01*
Y-15844D01*
Y-15812D01*
Y-15780D01*
Y-15748D01*
Y-15715D01*
Y-15683D01*
Y-15651D01*
Y-15619D01*
Y-15586D01*
Y-15554D01*
Y-15522D01*
Y-15489D01*
Y-15457D01*
X470062Y-15425D01*
X470059Y-15393D01*
Y-15374D01*
X465474D01*
Y-15393D01*
Y-15425D01*
Y-15457D01*
Y-15489D01*
Y-15522D01*
Y-15554D01*
Y-15586D01*
Y-15619D01*
Y-15651D01*
Y-15683D01*
Y-15715D01*
Y-15748D01*
Y-15780D01*
Y-15812D01*
Y-15844D01*
Y-15877D01*
Y-15909D01*
Y-15941D01*
Y-15973D01*
Y-16006D01*
Y-16038D01*
Y-16070D01*
Y-16103D01*
Y-16135D01*
Y-16167D01*
Y-16199D01*
Y-16232D01*
Y-16264D01*
Y-16296D01*
Y-16328D01*
Y-16361D01*
Y-16393D01*
Y-16425D01*
Y-16457D01*
Y-16490D01*
Y-16522D01*
Y-16554D01*
Y-16586D01*
D01*
Y-16619D01*
Y-16651D01*
Y-16683D01*
Y-16715D01*
Y-16748D01*
Y-16780D01*
Y-16812D01*
Y-16845D01*
Y-16877D01*
Y-16909D01*
Y-16941D01*
Y-16974D01*
Y-17006D01*
Y-17038D01*
Y-17070D01*
Y-17103D01*
Y-17135D01*
Y-17167D01*
Y-17199D01*
Y-17232D01*
Y-17264D01*
Y-17296D01*
Y-17328D01*
Y-17361D01*
Y-17393D01*
Y-17425D01*
Y-17458D01*
Y-17490D01*
Y-17522D01*
Y-17554D01*
Y-17586D01*
Y-17619D01*
Y-17651D01*
Y-17683D01*
Y-17716D01*
Y-17748D01*
Y-17780D01*
Y-17812D01*
Y-17845D01*
Y-17877D01*
Y-17909D01*
Y-17941D01*
Y-17974D01*
X465470Y-18026D01*
X465460Y-18077D01*
X465443Y-18127D01*
X465420Y-18174D01*
X465391Y-18218D01*
X465356Y-18257D01*
X465317Y-18292D01*
X465273Y-18321D01*
X465226Y-18344D01*
X465176Y-18361D01*
X465125Y-18371D01*
X465073Y-18374D01*
X460266D01*
X460213Y-18371D01*
X460162Y-18361D01*
X460112Y-18344D01*
X460065Y-18321D01*
X460022Y-18292D01*
X459982Y-18257D01*
X459948Y-18218D01*
X459918Y-18174D01*
X459895Y-18127D01*
X459878Y-18077D01*
X459868Y-18026D01*
X459865Y-17974D01*
Y-17941D01*
Y-17909D01*
Y-17877D01*
Y-17845D01*
Y-17812D01*
Y-17780D01*
Y-17748D01*
Y-17716D01*
Y-17683D01*
Y-17651D01*
Y-17619D01*
Y-17586D01*
Y-17554D01*
Y-17522D01*
Y-17490D01*
Y-17458D01*
Y-17425D01*
Y-17393D01*
Y-17361D01*
Y-17328D01*
Y-17296D01*
Y-17264D01*
Y-17232D01*
Y-17199D01*
Y-17167D01*
Y-17135D01*
Y-17103D01*
Y-17070D01*
Y-17038D01*
Y-17006D01*
Y-16974D01*
Y-16941D01*
Y-16909D01*
Y-16877D01*
Y-16845D01*
Y-16812D01*
Y-16780D01*
Y-16748D01*
Y-16715D01*
Y-16683D01*
Y-16651D01*
Y-16619D01*
Y-16586D01*
D01*
Y-16554D01*
Y-16522D01*
Y-16490D01*
Y-16457D01*
Y-16425D01*
Y-16393D01*
Y-16361D01*
Y-16328D01*
Y-16296D01*
Y-16264D01*
Y-16232D01*
Y-16199D01*
Y-16167D01*
Y-16135D01*
Y-16103D01*
Y-16070D01*
Y-16038D01*
Y-16006D01*
Y-15973D01*
Y-15941D01*
Y-15909D01*
Y-15877D01*
Y-15844D01*
Y-15812D01*
Y-15780D01*
Y-15748D01*
Y-15715D01*
Y-15683D01*
Y-15651D01*
Y-15619D01*
Y-15586D01*
Y-15554D01*
Y-15522D01*
Y-15489D01*
Y-15457D01*
Y-15425D01*
Y-15393D01*
Y-15360D01*
Y-15328D01*
Y-15296D01*
Y-15264D01*
Y-15231D01*
Y-15199D01*
Y-15167D01*
Y-15135D01*
Y-15102D01*
Y-15070D01*
X459868Y-15018D01*
X459878Y-14966D01*
X459895Y-14917D01*
X459918Y-14870D01*
X459948Y-14826D01*
X459982Y-14787D01*
X460022Y-14752D01*
X460065Y-14723D01*
X460112Y-14700D01*
X460162Y-14683D01*
X460213Y-14673D01*
X460266Y-14669D01*
X460734D01*
X460699Y-14646D01*
X460660Y-14612D01*
X460645Y-14594D01*
X460643Y-14593D01*
X460614Y-14579D01*
X460570Y-14549D01*
X460531Y-14515D01*
X460515Y-14498D01*
X460498Y-14482D01*
X460483Y-14465D01*
X460466Y-14450D01*
X460451Y-14433D01*
X460434Y-14418D01*
X460419Y-14401D01*
X460402Y-14386D01*
X460387Y-14369D01*
X460369Y-14354D01*
X460335Y-14314D01*
X460306Y-14270D01*
X460291Y-14241D01*
X460270Y-14217D01*
X460241Y-14174D01*
X460218Y-14127D01*
X460215Y-14119D01*
X460209Y-14109D01*
X460186Y-14062D01*
X460183Y-14054D01*
X460177Y-14045D01*
X460153Y-13998D01*
X460151Y-13990D01*
X460144Y-13980D01*
X460121Y-13933D01*
X460118Y-13925D01*
X460112Y-13916D01*
X460089Y-13869D01*
X460072Y-13819D01*
X460068Y-13800D01*
X460067Y-13792D01*
X460057Y-13772D01*
X460040Y-13722D01*
X460030Y-13671D01*
X460026Y-13618D01*
Y-13614D01*
X460024Y-13610D01*
X460007Y-13561D01*
X459997Y-13509D01*
X459994Y-13457D01*
Y-13425D01*
Y-13393D01*
Y-13360D01*
Y-13328D01*
Y-13296D01*
Y-13263D01*
Y-13231D01*
Y-13199D01*
Y-13167D01*
Y-13134D01*
X459997Y-13082D01*
X460007Y-13031D01*
X460024Y-12981D01*
X460026Y-12978D01*
Y-12973D01*
X460030Y-12921D01*
X460040Y-12869D01*
X460057Y-12820D01*
X460067Y-12799D01*
X460072Y-12773D01*
X460089Y-12723D01*
X460112Y-12676D01*
X460118Y-12666D01*
X460121Y-12658D01*
X460144Y-12611D01*
X460145Y-12610D01*
X460151Y-12602D01*
X460153Y-12594D01*
X460177Y-12547D01*
X460183Y-12537D01*
X460186Y-12529D01*
X460209Y-12482D01*
X460215Y-12473D01*
X460218Y-12465D01*
X460241Y-12418D01*
X460270Y-12374D01*
X460291Y-12350D01*
X460306Y-12321D01*
X460335Y-12277D01*
X460369Y-12238D01*
X460387Y-12223D01*
X460402Y-12206D01*
X460419Y-12191D01*
X460434Y-12173D01*
X460451Y-12158D01*
X460466Y-12141D01*
X460483Y-12126D01*
X460498Y-12109D01*
X460515Y-12094D01*
X460531Y-12077D01*
X460548Y-12062D01*
X460563Y-12044D01*
X460602Y-12010D01*
X460646Y-11981D01*
X460675Y-11966D01*
X460699Y-11945D01*
X460734Y-11922D01*
X460266D01*
X460213Y-11919D01*
X460162Y-11908D01*
X460112Y-11892D01*
X460065Y-11868D01*
X460022Y-11839D01*
X459982Y-11805D01*
X459948Y-11765D01*
X459918Y-11722D01*
X459895Y-11675D01*
X459878Y-11625D01*
X459868Y-11574D01*
X459865Y-11521D01*
Y-11489D01*
Y-11457D01*
Y-11425D01*
Y-11392D01*
Y-11360D01*
Y-11328D01*
Y-11295D01*
Y-11263D01*
Y-11231D01*
Y-11199D01*
Y-11167D01*
Y-11134D01*
Y-11102D01*
Y-11070D01*
Y-11037D01*
Y-11005D01*
Y-10973D01*
Y-10941D01*
Y-10908D01*
Y-10876D01*
Y-10844D01*
Y-10812D01*
Y-10779D01*
Y-10747D01*
Y-10715D01*
X459868Y-10662D01*
X459878Y-10611D01*
X459895Y-10561D01*
X459918Y-10514D01*
X459948Y-10471D01*
X459982Y-10431D01*
X460022Y-10397D01*
X460065Y-10368D01*
X460112Y-10344D01*
X460162Y-10328D01*
X460213Y-10317D01*
X460266Y-10314D01*
X460766D01*
X460766Y-10314D01*
X460757Y-10311D01*
X460710Y-10288D01*
X460667Y-10259D01*
X460628Y-10224D01*
X460612Y-10207D01*
X460611Y-10205D01*
X460581Y-10191D01*
X460538Y-10162D01*
X460498Y-10127D01*
X460483Y-10110D01*
X460466Y-10095D01*
X460451Y-10078D01*
X460434Y-10063D01*
X460419Y-10046D01*
X460402Y-10030D01*
X460367Y-9991D01*
X460338Y-9947D01*
X460323Y-9918D01*
X460322Y-9916D01*
X460305Y-9901D01*
X460270Y-9862D01*
X460241Y-9818D01*
X460218Y-9771D01*
X460215Y-9763D01*
X460209Y-9754D01*
X460186Y-9707D01*
X460183Y-9699D01*
X460177Y-9689D01*
X460153Y-9642D01*
X460151Y-9634D01*
X460144Y-9625D01*
X460121Y-9578D01*
X460119Y-9570D01*
X460118Y-9570D01*
X460112Y-9560D01*
X460089Y-9513D01*
X460072Y-9464D01*
X460067Y-9437D01*
X460057Y-9416D01*
X460040Y-9367D01*
X460030Y-9315D01*
X460026Y-9263D01*
Y-9259D01*
X460024Y-9255D01*
X460007Y-9206D01*
X459997Y-9154D01*
X459994Y-9102D01*
Y-9069D01*
Y-9037D01*
Y-9005D01*
Y-8973D01*
Y-8940D01*
Y-8908D01*
Y-8876D01*
Y-8844D01*
Y-8811D01*
Y-8779D01*
X459997Y-8727D01*
X460007Y-8675D01*
X460024Y-8626D01*
X460026Y-8622D01*
Y-8618D01*
X460030Y-8565D01*
X460040Y-8514D01*
X460057Y-8464D01*
X460067Y-8444D01*
X460072Y-8417D01*
X460089Y-8368D01*
X460099Y-8347D01*
X460104Y-8320D01*
X460121Y-8271D01*
X460144Y-8224D01*
X460151Y-8214D01*
X460153Y-8206D01*
X460177Y-8159D01*
X460183Y-8150D01*
X460186Y-8142D01*
X460209Y-8095D01*
X460238Y-8051D01*
X460259Y-8027D01*
X460273Y-7998D01*
X460302Y-7954D01*
X460337Y-7915D01*
X460354Y-7900D01*
X460369Y-7883D01*
X460387Y-7868D01*
X460402Y-7850D01*
X460419Y-7835D01*
X460434Y-7818D01*
X460451Y-7803D01*
X460466Y-7786D01*
X460483Y-7771D01*
X460498Y-7754D01*
X460515Y-7739D01*
X460531Y-7721D01*
X460548Y-7706D01*
X460563Y-7689D01*
X460580Y-7674D01*
X460595Y-7657D01*
X460635Y-7622D01*
X460678Y-7593D01*
X460725Y-7570D01*
X460733Y-7567D01*
X460734Y-7567D01*
X460298D01*
X460246Y-7563D01*
X460194Y-7553D01*
X460145Y-7536D01*
X460098Y-7513D01*
X460054Y-7484D01*
X460014Y-7450D01*
X459999Y-7432D01*
X459982Y-7417D01*
X459948Y-7378D01*
X459918Y-7334D01*
X459895Y-7287D01*
X459878Y-7237D01*
X459868Y-7186D01*
X459865Y-7134D01*
Y-7102D01*
Y-7069D01*
Y-7037D01*
Y-7005D01*
Y-6972D01*
Y-6940D01*
Y-6908D01*
Y-6876D01*
Y-6843D01*
Y-6811D01*
Y-6779D01*
Y-6747D01*
Y-6714D01*
Y-6682D01*
Y-6650D01*
Y-6617D01*
Y-6585D01*
Y-6553D01*
Y-6521D01*
Y-6488D01*
Y-6456D01*
Y-6424D01*
Y-6392D01*
Y-6359D01*
X459868Y-6307D01*
X459878Y-6256D01*
X459895Y-6206D01*
X459918Y-6159D01*
X459948Y-6115D01*
X459982Y-6076D01*
X460022Y-6041D01*
X460065Y-6012D01*
X460112Y-5989D01*
X460162Y-5972D01*
X460213Y-5962D01*
X460266Y-5959D01*
X460766D01*
X460731Y-5935D01*
X460708Y-5914D01*
X460678Y-5900D01*
X460635Y-5871D01*
X460595Y-5836D01*
X460580Y-5819D01*
X460580Y-5819D01*
X460563Y-5804D01*
X460548Y-5787D01*
X460531Y-5772D01*
X460515Y-5754D01*
X460498Y-5740D01*
X460483Y-5722D01*
X460466Y-5707D01*
X460451Y-5690D01*
X460434Y-5675D01*
X460419Y-5658D01*
X460402Y-5643D01*
X460387Y-5626D01*
X460369Y-5610D01*
X460354Y-5593D01*
X460337Y-5578D01*
X460302Y-5539D01*
X460273Y-5495D01*
X460259Y-5466D01*
X460238Y-5442D01*
X460209Y-5398D01*
X460186Y-5351D01*
X460183Y-5343D01*
X460177Y-5334D01*
X460153Y-5287D01*
X460151Y-5279D01*
X460144Y-5269D01*
X460121Y-5222D01*
X460104Y-5173D01*
X460099Y-5146D01*
X460089Y-5126D01*
X460072Y-5076D01*
X460067Y-5049D01*
X460057Y-5029D01*
X460040Y-4979D01*
X460030Y-4928D01*
X460028Y-4908D01*
X460024Y-4900D01*
X460007Y-4850D01*
X459997Y-4799D01*
X459994Y-4746D01*
Y-4714D01*
Y-4682D01*
Y-4650D01*
Y-4617D01*
Y-4585D01*
Y-4553D01*
Y-4521D01*
Y-4488D01*
Y-4456D01*
Y-4424D01*
Y-4391D01*
X459997Y-4339D01*
X460007Y-4288D01*
X460024Y-4238D01*
X460028Y-4230D01*
X460030Y-4210D01*
X460040Y-4159D01*
X460057Y-4109D01*
X460061Y-4101D01*
X460062Y-4081D01*
X460072Y-4030D01*
X460089Y-3980D01*
X460112Y-3933D01*
X460118Y-3923D01*
X460121Y-3915D01*
X460144Y-3868D01*
X460145Y-3867D01*
X460151Y-3859D01*
X460153Y-3851D01*
X460177Y-3804D01*
X460183Y-3794D01*
X460186Y-3786D01*
X460209Y-3739D01*
X460238Y-3696D01*
X460256Y-3675D01*
X460259Y-3672D01*
X460273Y-3643D01*
X460302Y-3599D01*
X460337Y-3560D01*
X460354Y-3545D01*
X460369Y-3527D01*
X460387Y-3512D01*
X460402Y-3495D01*
X460419Y-3480D01*
X460434Y-3463D01*
X460451Y-3448D01*
X460466Y-3430D01*
X460483Y-3416D01*
X460498Y-3398D01*
X460515Y-3383D01*
X460531Y-3366D01*
X460548Y-3351D01*
X460563Y-3334D01*
X460580Y-3319D01*
X460595Y-3302D01*
X460635Y-3267D01*
X460678Y-3238D01*
X460685Y-3235D01*
X460708Y-3223D01*
X460731Y-3202D01*
X460766Y-3179D01*
X460266D01*
X460213Y-3176D01*
X460162Y-3166D01*
X460112Y-3149D01*
X460065Y-3125D01*
X460022Y-3096D01*
X459982Y-3062D01*
X459948Y-3022D01*
X459918Y-2979D01*
X459895Y-2932D01*
X459878Y-2882D01*
X459868Y-2831D01*
X459865Y-2778D01*
Y-2746D01*
Y-2714D01*
Y-2682D01*
Y-2649D01*
Y-2617D01*
Y-2585D01*
Y-2553D01*
Y-2520D01*
Y-2488D01*
Y-2456D01*
Y-2424D01*
Y-2391D01*
Y-2359D01*
Y-2327D01*
Y-2294D01*
Y-2262D01*
Y-2230D01*
Y-2198D01*
Y-2165D01*
Y-2133D01*
Y-2101D01*
Y-2069D01*
Y-2036D01*
Y-2004D01*
X459868Y-1952D01*
X459878Y-1900D01*
X459895Y-1851D01*
X459918Y-1804D01*
X459948Y-1760D01*
X459982Y-1721D01*
X459999Y-1706D01*
X460014Y-1688D01*
X460054Y-1654D01*
X460098Y-1625D01*
X460145Y-1602D01*
X460194Y-1585D01*
X460246Y-1574D01*
X460298Y-1571D01*
X460734D01*
X460699Y-1548D01*
X460675Y-1527D01*
X460646Y-1512D01*
X460602Y-1483D01*
X460563Y-1449D01*
X460548Y-1431D01*
X460531Y-1417D01*
X460516Y-1399D01*
X460498Y-1384D01*
X460483Y-1367D01*
X460466Y-1352D01*
X460451Y-1335D01*
X460434Y-1320D01*
X460419Y-1303D01*
X460402Y-1287D01*
X460387Y-1270D01*
X460369Y-1255D01*
X460354Y-1238D01*
X460337Y-1223D01*
X460302Y-1183D01*
X460273Y-1140D01*
X460250Y-1093D01*
X460248Y-1085D01*
X460241Y-1075D01*
X460227Y-1046D01*
X460206Y-1022D01*
X460177Y-979D01*
X460153Y-932D01*
X460151Y-924D01*
X460144Y-914D01*
X460121Y-867D01*
X460104Y-817D01*
X460099Y-791D01*
X460089Y-770D01*
X460072Y-721D01*
X460067Y-694D01*
X460057Y-673D01*
X460040Y-624D01*
X460030Y-572D01*
X460026Y-520D01*
Y-516D01*
X460024Y-512D01*
X460007Y-463D01*
X459997Y-411D01*
X459994Y-359D01*
Y-326D01*
Y-294D01*
Y-262D01*
Y-230D01*
Y-197D01*
Y-165D01*
Y-133D01*
Y-101D01*
Y-68D01*
Y-36D01*
X459997Y16D01*
X460007Y68D01*
X460024Y117D01*
X460026Y121D01*
Y125D01*
X460030Y178D01*
X460040Y229D01*
X460057Y279D01*
X460067Y299D01*
X460072Y326D01*
X460089Y375D01*
X460112Y422D01*
X460118Y432D01*
X460121Y440D01*
X460144Y487D01*
X460151Y496D01*
X460153Y504D01*
X460177Y551D01*
X460177Y552D01*
X460183Y561D01*
X460186Y569D01*
X460209Y616D01*
X460215Y625D01*
X460218Y634D01*
X460241Y680D01*
X460270Y724D01*
X460305Y764D01*
X460322Y778D01*
X460323Y780D01*
X460338Y809D01*
X460367Y853D01*
X460402Y893D01*
X460417Y906D01*
X460419Y908D01*
X460434Y925D01*
X460451Y940D01*
X460466Y957D01*
X460469Y959D01*
X460483Y972D01*
X460498Y989D01*
X460538Y1024D01*
X460581Y1053D01*
X460611Y1068D01*
X460612Y1069D01*
X460628Y1086D01*
X460667Y1121D01*
X460710Y1150D01*
X460740Y1164D01*
X460753Y1176D01*
X460266D01*
X460213Y1180D01*
X460162Y1190D01*
X460112Y1207D01*
X460065Y1230D01*
X460022Y1259D01*
X459982Y1293D01*
X459948Y1333D01*
X459918Y1376D01*
X459895Y1424D01*
X459878Y1473D01*
X459868Y1525D01*
X459865Y1577D01*
Y1609D01*
Y1641D01*
Y1674D01*
Y1706D01*
Y1738D01*
Y1770D01*
Y1803D01*
Y1835D01*
Y1867D01*
Y1900D01*
Y1932D01*
Y1964D01*
Y1996D01*
Y2029D01*
Y2061D01*
Y2093D01*
Y2125D01*
Y2158D01*
Y2190D01*
Y2222D01*
Y2254D01*
Y2287D01*
Y2319D01*
Y2351D01*
Y2383D01*
Y2416D01*
Y2448D01*
Y2480D01*
Y2513D01*
Y2545D01*
Y2577D01*
Y2609D01*
Y2642D01*
Y2674D01*
Y2706D01*
Y2738D01*
Y2771D01*
Y2803D01*
Y2835D01*
Y2867D01*
Y2900D01*
Y2932D01*
Y2964D01*
Y2997D01*
Y3029D01*
Y3061D01*
Y3093D01*
Y3125D01*
Y3158D01*
Y3190D01*
Y3222D01*
Y3255D01*
Y3287D01*
Y3319D01*
Y3351D01*
Y3384D01*
Y3416D01*
Y3448D01*
Y3480D01*
Y3513D01*
Y3545D01*
Y3577D01*
Y3609D01*
Y3642D01*
Y3674D01*
Y3706D01*
Y3739D01*
Y3771D01*
Y3803D01*
Y3835D01*
Y3867D01*
Y3900D01*
Y3932D01*
Y3964D01*
Y3997D01*
Y4029D01*
Y4061D01*
Y4093D01*
Y4126D01*
Y4158D01*
Y4190D01*
Y4222D01*
Y4255D01*
Y4287D01*
Y4319D01*
Y4352D01*
Y4384D01*
Y4416D01*
Y4448D01*
Y4481D01*
Y4513D01*
Y4545D01*
Y4577D01*
Y4610D01*
Y4642D01*
Y4674D01*
Y4706D01*
Y4739D01*
Y4771D01*
Y4803D01*
Y4835D01*
Y4868D01*
Y4900D01*
Y4932D01*
Y4964D01*
Y4997D01*
Y5029D01*
Y5061D01*
Y5094D01*
Y5126D01*
Y5158D01*
Y5190D01*
Y5223D01*
Y5255D01*
Y5287D01*
Y5319D01*
Y5352D01*
Y5384D01*
Y5416D01*
Y5448D01*
Y5481D01*
Y5513D01*
Y5545D01*
Y5577D01*
Y5610D01*
Y5642D01*
Y5674D01*
Y5706D01*
Y5739D01*
Y5771D01*
Y5803D01*
Y5835D01*
Y5868D01*
Y5900D01*
Y5932D01*
Y5965D01*
Y5997D01*
Y6029D01*
Y6061D01*
Y6094D01*
Y6126D01*
Y6158D01*
Y6190D01*
Y6223D01*
Y6255D01*
Y6287D01*
Y6319D01*
Y6352D01*
Y6384D01*
Y6416D01*
Y6448D01*
Y6481D01*
Y6513D01*
Y6545D01*
Y6577D01*
Y6610D01*
Y6642D01*
Y6674D01*
Y6707D01*
Y6739D01*
Y6771D01*
Y6803D01*
Y6836D01*
Y6868D01*
Y6900D01*
Y6932D01*
Y6965D01*
Y6997D01*
Y7029D01*
Y7062D01*
Y7094D01*
Y7126D01*
Y7158D01*
Y7191D01*
Y7223D01*
Y7255D01*
Y7287D01*
Y7320D01*
Y7352D01*
Y7384D01*
Y7416D01*
Y7449D01*
Y7481D01*
Y7513D01*
Y7545D01*
Y7578D01*
Y7610D01*
Y7642D01*
Y7674D01*
Y7707D01*
Y7739D01*
Y7771D01*
Y7803D01*
Y7836D01*
Y7868D01*
Y7900D01*
Y7932D01*
Y7965D01*
Y7997D01*
Y8029D01*
Y8062D01*
Y8094D01*
Y8126D01*
Y8158D01*
Y8191D01*
Y8223D01*
Y8255D01*
Y8287D01*
Y8320D01*
Y8352D01*
Y8384D01*
Y8416D01*
Y8449D01*
Y8481D01*
Y8513D01*
Y8546D01*
Y8578D01*
Y8610D01*
Y8642D01*
Y8675D01*
Y8707D01*
Y8739D01*
Y8771D01*
Y8804D01*
Y8836D01*
Y8868D01*
Y8900D01*
Y8933D01*
Y8965D01*
Y8997D01*
Y9029D01*
Y9062D01*
Y9094D01*
Y9126D01*
Y9159D01*
Y9191D01*
Y9223D01*
Y9255D01*
Y9287D01*
Y9320D01*
Y9352D01*
Y9384D01*
Y9417D01*
Y9449D01*
Y9481D01*
Y9513D01*
Y9546D01*
Y9578D01*
Y9610D01*
Y9642D01*
Y9675D01*
Y9707D01*
Y9739D01*
Y9771D01*
Y9804D01*
Y9836D01*
Y9868D01*
Y9900D01*
Y9933D01*
Y9965D01*
Y9997D01*
Y10029D01*
Y10062D01*
Y10094D01*
Y10126D01*
Y10159D01*
Y10191D01*
Y10223D01*
Y10255D01*
Y10288D01*
Y10320D01*
Y10352D01*
Y10384D01*
Y10417D01*
Y10449D01*
Y10481D01*
Y10514D01*
Y10546D01*
Y10578D01*
Y10610D01*
Y10643D01*
Y10675D01*
Y10707D01*
Y10739D01*
Y10772D01*
Y10804D01*
Y10836D01*
Y10868D01*
Y10901D01*
Y10933D01*
Y10965D01*
Y10997D01*
Y11030D01*
Y11062D01*
Y11094D01*
Y11126D01*
Y11159D01*
Y11191D01*
Y11223D01*
Y11255D01*
Y11288D01*
Y11320D01*
Y11352D01*
Y11384D01*
Y11417D01*
Y11449D01*
Y11481D01*
Y11514D01*
Y11546D01*
Y11578D01*
Y11610D01*
Y11643D01*
Y11675D01*
Y11707D01*
Y11739D01*
Y11772D01*
Y11804D01*
Y11836D01*
Y11868D01*
Y11901D01*
Y11933D01*
Y11965D01*
Y11998D01*
Y12030D01*
Y12062D01*
Y12094D01*
Y12127D01*
Y12159D01*
Y12191D01*
Y12223D01*
Y12256D01*
Y12288D01*
Y12320D01*
Y12352D01*
Y12385D01*
Y12417D01*
Y12449D01*
Y12481D01*
Y12514D01*
Y12546D01*
Y12578D01*
Y12610D01*
Y12643D01*
Y12675D01*
Y12707D01*
Y12740D01*
Y12772D01*
Y12804D01*
Y12836D01*
Y12869D01*
Y12901D01*
Y12933D01*
Y12965D01*
Y12998D01*
Y13030D01*
Y13062D01*
Y13094D01*
Y13127D01*
Y13159D01*
Y13191D01*
Y13223D01*
Y13256D01*
Y13288D01*
Y13320D01*
Y13352D01*
Y13385D01*
Y13417D01*
Y13449D01*
Y13482D01*
Y13514D01*
Y13546D01*
Y13578D01*
Y13611D01*
Y13643D01*
Y13675D01*
Y13707D01*
Y13740D01*
Y13772D01*
Y13804D01*
Y13836D01*
Y13869D01*
Y13901D01*
Y13933D01*
Y13965D01*
Y13998D01*
Y14030D01*
Y14062D01*
Y14095D01*
Y14127D01*
Y14159D01*
Y14191D01*
Y14224D01*
Y14256D01*
Y14288D01*
Y14320D01*
Y14353D01*
Y14385D01*
Y14417D01*
Y14449D01*
X459868Y14502D01*
X459878Y14553D01*
X459895Y14603D01*
X459918Y14650D01*
X459948Y14693D01*
X459982Y14733D01*
X459999Y14748D01*
X460014Y14765D01*
X460054Y14800D01*
X460098Y14829D01*
X460145Y14852D01*
X460194Y14869D01*
X460246Y14879D01*
X460298Y14883D01*
X501012D01*
X501065Y14879D01*
D02*
G37*
G36*
X457221D02*
X457272Y14869D01*
X457322Y14852D01*
X457326Y14850D01*
X457491D01*
X457544Y14847D01*
X457595Y14837D01*
X457645Y14820D01*
X457652Y14816D01*
X457673Y14815D01*
X457724Y14804D01*
X457774Y14787D01*
X457782Y14784D01*
X457802Y14782D01*
X457853Y14772D01*
X457903Y14755D01*
X457950Y14732D01*
X457959Y14726D01*
X457967Y14723D01*
X457988Y14713D01*
X458014Y14708D01*
X458064Y14691D01*
X458111Y14668D01*
X458120Y14661D01*
X458128Y14658D01*
X458176Y14635D01*
X458185Y14629D01*
X458193Y14626D01*
X458240Y14603D01*
X458250Y14597D01*
X458257Y14594D01*
X458305Y14571D01*
X458314Y14564D01*
X458322Y14562D01*
X458369Y14538D01*
X458413Y14509D01*
X458437Y14488D01*
X458466Y14474D01*
X458509Y14445D01*
X458549Y14410D01*
X458564Y14393D01*
X458566Y14392D01*
X458595Y14377D01*
X458638Y14348D01*
X458678Y14313D01*
X458693Y14296D01*
X458710Y14281D01*
X458725Y14264D01*
X458743Y14249D01*
X458757Y14232D01*
X458767Y14224D01*
X458775Y14217D01*
X458790Y14199D01*
X458807Y14184D01*
X458822Y14167D01*
X458831Y14159D01*
X458839Y14152D01*
X458854Y14135D01*
X458872Y14120D01*
X458887Y14103D01*
X458904Y14088D01*
X458919Y14070D01*
X458936Y14055D01*
X458971Y14016D01*
X459000Y13972D01*
X459014Y13943D01*
X459016Y13941D01*
X459033Y13926D01*
X459067Y13887D01*
X459096Y13843D01*
X459111Y13814D01*
X459132Y13790D01*
X459161Y13747D01*
X459184Y13700D01*
X459187Y13691D01*
X459193Y13682D01*
X459216Y13635D01*
X459219Y13627D01*
X459226Y13617D01*
X459249Y13570D01*
X459251Y13562D01*
X459258Y13553D01*
X459281Y13506D01*
X459284Y13498D01*
X459290Y13488D01*
X459313Y13441D01*
X459330Y13392D01*
X459336Y13365D01*
X459345Y13345D01*
X459348Y13337D01*
X459355Y13327D01*
X459378Y13280D01*
X459395Y13230D01*
X459405Y13179D01*
X459406Y13159D01*
X459410Y13151D01*
X459427Y13101D01*
X459437Y13050D01*
X459441Y12998D01*
Y12993D01*
X459442Y12990D01*
X459459Y12940D01*
X459469Y12889D01*
X459473Y12836D01*
Y12804D01*
Y12772D01*
Y12740D01*
Y12707D01*
Y12675D01*
Y12643D01*
Y12610D01*
Y12578D01*
Y12546D01*
Y12514D01*
Y12481D01*
Y12449D01*
Y12417D01*
Y12385D01*
Y12352D01*
Y12320D01*
Y12288D01*
Y12256D01*
Y12223D01*
Y12191D01*
Y12159D01*
Y12127D01*
Y12094D01*
Y12062D01*
Y12030D01*
Y11998D01*
Y11965D01*
Y11933D01*
Y11901D01*
Y11868D01*
Y11836D01*
Y11804D01*
Y11772D01*
Y11739D01*
Y11707D01*
Y11675D01*
Y11643D01*
Y11610D01*
Y11578D01*
Y11546D01*
Y11514D01*
Y11481D01*
Y11449D01*
Y11417D01*
Y11384D01*
Y11352D01*
Y11320D01*
Y11288D01*
Y11255D01*
Y11223D01*
Y11191D01*
Y11159D01*
Y11126D01*
Y11094D01*
Y11062D01*
Y11030D01*
Y10997D01*
Y10965D01*
Y10933D01*
Y10901D01*
Y10868D01*
Y10836D01*
Y10804D01*
Y10772D01*
Y10739D01*
Y10707D01*
Y10675D01*
Y10643D01*
Y10610D01*
Y10578D01*
Y10546D01*
Y10514D01*
Y10481D01*
Y10449D01*
Y10417D01*
Y10384D01*
Y10352D01*
Y10320D01*
Y10288D01*
Y10255D01*
Y10223D01*
Y10191D01*
Y10159D01*
Y10126D01*
Y10094D01*
Y10062D01*
Y10029D01*
Y9997D01*
Y9965D01*
Y9933D01*
Y9900D01*
Y9868D01*
Y9836D01*
Y9804D01*
Y9771D01*
Y9739D01*
Y9707D01*
Y9675D01*
Y9642D01*
Y9610D01*
Y9578D01*
Y9546D01*
Y9513D01*
Y9481D01*
Y9449D01*
Y9417D01*
Y9384D01*
Y9352D01*
Y9320D01*
Y9287D01*
Y9255D01*
Y9223D01*
Y9191D01*
Y9159D01*
Y9126D01*
Y9094D01*
Y9062D01*
Y9029D01*
Y8997D01*
Y8965D01*
Y8933D01*
Y8900D01*
Y8868D01*
Y8836D01*
Y8804D01*
Y8771D01*
Y8739D01*
Y8707D01*
Y8675D01*
Y8642D01*
Y8610D01*
Y8578D01*
Y8546D01*
Y8513D01*
Y8481D01*
Y8449D01*
Y8416D01*
Y8384D01*
Y8352D01*
Y8320D01*
Y8287D01*
Y8255D01*
Y8223D01*
Y8191D01*
Y8158D01*
Y8126D01*
Y8094D01*
Y8062D01*
Y8029D01*
Y7997D01*
Y7965D01*
Y7932D01*
Y7900D01*
Y7868D01*
Y7836D01*
Y7803D01*
Y7771D01*
Y7739D01*
Y7707D01*
Y7674D01*
Y7642D01*
Y7610D01*
Y7578D01*
Y7545D01*
Y7513D01*
Y7481D01*
Y7449D01*
Y7416D01*
Y7384D01*
Y7352D01*
Y7320D01*
Y7287D01*
Y7255D01*
Y7223D01*
Y7191D01*
Y7158D01*
Y7126D01*
Y7094D01*
Y7062D01*
Y7029D01*
Y6997D01*
Y6965D01*
Y6932D01*
Y6900D01*
Y6868D01*
Y6836D01*
Y6803D01*
Y6771D01*
Y6739D01*
Y6707D01*
Y6674D01*
Y6642D01*
Y6610D01*
Y6577D01*
Y6545D01*
Y6513D01*
Y6481D01*
Y6448D01*
Y6416D01*
Y6384D01*
Y6352D01*
Y6319D01*
Y6287D01*
Y6255D01*
Y6223D01*
Y6190D01*
Y6158D01*
Y6126D01*
Y6094D01*
Y6061D01*
Y6029D01*
Y5997D01*
Y5965D01*
Y5932D01*
Y5900D01*
Y5868D01*
Y5835D01*
Y5803D01*
Y5771D01*
Y5739D01*
Y5706D01*
Y5674D01*
Y5642D01*
Y5610D01*
Y5577D01*
Y5545D01*
Y5513D01*
Y5481D01*
Y5448D01*
Y5416D01*
Y5384D01*
Y5352D01*
Y5319D01*
Y5287D01*
Y5255D01*
Y5223D01*
Y5190D01*
Y5158D01*
Y5126D01*
Y5094D01*
D01*
Y5061D01*
Y5029D01*
Y4997D01*
Y4964D01*
Y4932D01*
Y4900D01*
Y4868D01*
Y4835D01*
Y4803D01*
Y4771D01*
Y4739D01*
Y4706D01*
Y4674D01*
Y4642D01*
Y4610D01*
Y4577D01*
Y4545D01*
Y4513D01*
Y4481D01*
Y4448D01*
Y4416D01*
Y4384D01*
Y4352D01*
Y4319D01*
Y4287D01*
Y4255D01*
Y4222D01*
Y4190D01*
Y4158D01*
Y4126D01*
Y4093D01*
Y4061D01*
Y4029D01*
Y3997D01*
Y3964D01*
Y3932D01*
Y3900D01*
Y3867D01*
Y3835D01*
Y3803D01*
Y3771D01*
Y3739D01*
Y3706D01*
Y3674D01*
Y3642D01*
Y3609D01*
Y3577D01*
Y3545D01*
Y3513D01*
Y3480D01*
Y3448D01*
Y3416D01*
Y3384D01*
Y3351D01*
Y3319D01*
Y3287D01*
Y3255D01*
Y3222D01*
Y3190D01*
Y3158D01*
Y3125D01*
Y3093D01*
Y3061D01*
Y3029D01*
Y2997D01*
Y2964D01*
Y2932D01*
Y2900D01*
Y2867D01*
Y2835D01*
Y2803D01*
Y2771D01*
Y2738D01*
Y2706D01*
Y2674D01*
Y2642D01*
Y2609D01*
Y2577D01*
Y2545D01*
Y2513D01*
Y2480D01*
Y2448D01*
Y2416D01*
Y2383D01*
Y2351D01*
Y2319D01*
Y2287D01*
Y2254D01*
Y2222D01*
Y2190D01*
Y2158D01*
Y2125D01*
Y2093D01*
Y2061D01*
Y2029D01*
Y1996D01*
Y1964D01*
Y1932D01*
Y1900D01*
Y1867D01*
Y1835D01*
Y1803D01*
Y1770D01*
Y1738D01*
Y1706D01*
Y1674D01*
Y1641D01*
Y1609D01*
Y1577D01*
Y1545D01*
Y1512D01*
Y1480D01*
Y1448D01*
Y1416D01*
Y1383D01*
Y1351D01*
Y1319D01*
Y1287D01*
Y1254D01*
Y1222D01*
Y1190D01*
Y1158D01*
Y1125D01*
Y1093D01*
Y1061D01*
Y1029D01*
Y996D01*
Y964D01*
Y932D01*
Y900D01*
Y867D01*
Y835D01*
Y803D01*
Y770D01*
Y738D01*
Y706D01*
Y674D01*
Y641D01*
Y609D01*
Y577D01*
Y545D01*
Y512D01*
Y480D01*
Y448D01*
Y416D01*
Y383D01*
Y351D01*
Y319D01*
Y286D01*
Y254D01*
Y222D01*
Y190D01*
Y157D01*
Y125D01*
Y93D01*
Y61D01*
Y28D01*
Y-4D01*
Y-36D01*
Y-68D01*
Y-101D01*
Y-133D01*
Y-165D01*
Y-197D01*
Y-230D01*
Y-262D01*
Y-294D01*
Y-326D01*
Y-359D01*
Y-391D01*
Y-423D01*
Y-455D01*
Y-488D01*
Y-520D01*
Y-552D01*
Y-585D01*
Y-617D01*
Y-649D01*
Y-681D01*
Y-714D01*
Y-746D01*
Y-778D01*
Y-810D01*
Y-843D01*
Y-875D01*
Y-907D01*
Y-939D01*
Y-972D01*
Y-1004D01*
Y-1036D01*
Y-1068D01*
Y-1101D01*
Y-1133D01*
Y-1165D01*
Y-1198D01*
Y-1230D01*
Y-1262D01*
Y-1294D01*
Y-1327D01*
Y-1359D01*
Y-1391D01*
Y-1423D01*
Y-1456D01*
Y-1488D01*
Y-1520D01*
Y-1552D01*
Y-1585D01*
Y-1617D01*
Y-1649D01*
Y-1681D01*
Y-1714D01*
Y-1746D01*
Y-1778D01*
Y-1811D01*
Y-1843D01*
Y-1875D01*
Y-1907D01*
Y-1940D01*
Y-1972D01*
Y-2004D01*
Y-2036D01*
Y-2069D01*
Y-2101D01*
Y-2133D01*
Y-2165D01*
Y-2198D01*
Y-2230D01*
Y-2262D01*
Y-2294D01*
Y-2327D01*
Y-2359D01*
Y-2391D01*
Y-2424D01*
Y-2456D01*
Y-2488D01*
Y-2520D01*
Y-2553D01*
Y-2585D01*
Y-2617D01*
Y-2649D01*
Y-2682D01*
Y-2714D01*
Y-2746D01*
Y-2778D01*
Y-2811D01*
Y-2843D01*
Y-2875D01*
Y-2907D01*
Y-2940D01*
Y-2972D01*
Y-3004D01*
Y-3036D01*
Y-3069D01*
Y-3101D01*
Y-3133D01*
Y-3165D01*
Y-3198D01*
Y-3230D01*
Y-3262D01*
Y-3295D01*
Y-3327D01*
Y-3359D01*
Y-3391D01*
Y-3424D01*
Y-3456D01*
Y-3488D01*
Y-3520D01*
Y-3553D01*
Y-3585D01*
Y-3617D01*
Y-3650D01*
Y-3682D01*
Y-3714D01*
Y-3746D01*
Y-3779D01*
Y-3811D01*
Y-3843D01*
Y-3875D01*
Y-3907D01*
Y-3940D01*
Y-3972D01*
Y-4004D01*
Y-4037D01*
Y-4069D01*
Y-4101D01*
Y-4133D01*
Y-4166D01*
Y-4198D01*
Y-4230D01*
Y-4262D01*
Y-4295D01*
Y-4327D01*
Y-4359D01*
Y-4391D01*
Y-4424D01*
Y-4456D01*
Y-4488D01*
Y-4521D01*
Y-4553D01*
Y-4585D01*
Y-4617D01*
Y-4650D01*
Y-4682D01*
Y-4714D01*
Y-4746D01*
Y-4779D01*
Y-4811D01*
Y-4843D01*
Y-4875D01*
Y-4908D01*
Y-4940D01*
Y-4972D01*
Y-5004D01*
Y-5037D01*
Y-5069D01*
Y-5101D01*
Y-5133D01*
Y-5166D01*
Y-5198D01*
Y-5230D01*
Y-5263D01*
Y-5295D01*
Y-5327D01*
Y-5359D01*
Y-5392D01*
Y-5424D01*
Y-5456D01*
Y-5488D01*
Y-5521D01*
Y-5553D01*
Y-5585D01*
Y-5617D01*
Y-5650D01*
Y-5682D01*
Y-5714D01*
Y-5746D01*
Y-5779D01*
Y-5811D01*
D01*
Y-5843D01*
Y-5875D01*
Y-5908D01*
Y-5940D01*
Y-5972D01*
Y-6005D01*
Y-6037D01*
Y-6069D01*
Y-6101D01*
Y-6134D01*
Y-6166D01*
Y-6198D01*
Y-6230D01*
Y-6263D01*
Y-6295D01*
Y-6327D01*
Y-6359D01*
Y-6392D01*
Y-6424D01*
Y-6456D01*
Y-6488D01*
Y-6521D01*
Y-6553D01*
Y-6585D01*
Y-6617D01*
Y-6650D01*
Y-6682D01*
Y-6714D01*
Y-6747D01*
Y-6779D01*
Y-6811D01*
Y-6843D01*
Y-6876D01*
Y-6908D01*
Y-6940D01*
Y-6972D01*
Y-7005D01*
Y-7037D01*
Y-7069D01*
Y-7102D01*
Y-7134D01*
Y-7166D01*
Y-7198D01*
Y-7231D01*
Y-7263D01*
Y-7295D01*
Y-7327D01*
Y-7360D01*
Y-7392D01*
Y-7424D01*
Y-7456D01*
Y-7489D01*
Y-7521D01*
Y-7553D01*
Y-7585D01*
Y-7618D01*
Y-7650D01*
Y-7682D01*
Y-7714D01*
Y-7747D01*
Y-7779D01*
Y-7811D01*
Y-7843D01*
Y-7876D01*
Y-7908D01*
Y-7940D01*
Y-7972D01*
Y-8005D01*
Y-8037D01*
Y-8069D01*
Y-8102D01*
Y-8134D01*
Y-8166D01*
Y-8198D01*
Y-8231D01*
Y-8263D01*
Y-8295D01*
Y-8327D01*
Y-8360D01*
Y-8392D01*
Y-8424D01*
Y-8456D01*
Y-8489D01*
Y-8521D01*
Y-8553D01*
Y-8585D01*
Y-8618D01*
Y-8650D01*
Y-8682D01*
Y-8715D01*
Y-8747D01*
Y-8779D01*
Y-8811D01*
Y-8844D01*
Y-8876D01*
Y-8908D01*
Y-8940D01*
Y-8973D01*
Y-9005D01*
Y-9037D01*
Y-9069D01*
Y-9102D01*
Y-9134D01*
Y-9166D01*
Y-9199D01*
Y-9231D01*
Y-9263D01*
Y-9295D01*
Y-9328D01*
Y-9360D01*
Y-9392D01*
Y-9424D01*
Y-9457D01*
Y-9489D01*
Y-9521D01*
Y-9553D01*
Y-9586D01*
Y-9618D01*
Y-9650D01*
Y-9682D01*
Y-9715D01*
Y-9747D01*
Y-9779D01*
Y-9811D01*
Y-9844D01*
Y-9876D01*
Y-9908D01*
Y-9940D01*
Y-9973D01*
Y-10005D01*
Y-10037D01*
Y-10069D01*
Y-10102D01*
Y-10134D01*
Y-10166D01*
Y-10199D01*
Y-10231D01*
Y-10263D01*
Y-10295D01*
Y-10328D01*
Y-10360D01*
Y-10392D01*
Y-10424D01*
Y-10457D01*
Y-10489D01*
Y-10521D01*
Y-10554D01*
Y-10586D01*
Y-10618D01*
Y-10650D01*
Y-10683D01*
Y-10715D01*
Y-10747D01*
Y-10779D01*
Y-10812D01*
Y-10844D01*
Y-10876D01*
Y-10908D01*
Y-10941D01*
Y-10973D01*
Y-11005D01*
Y-11037D01*
Y-11070D01*
Y-11102D01*
Y-11134D01*
Y-11167D01*
Y-11199D01*
Y-11231D01*
Y-11263D01*
Y-11295D01*
Y-11328D01*
Y-11360D01*
Y-11392D01*
Y-11425D01*
Y-11457D01*
Y-11489D01*
Y-11521D01*
Y-11554D01*
Y-11586D01*
Y-11618D01*
Y-11650D01*
Y-11683D01*
Y-11715D01*
Y-11747D01*
Y-11779D01*
Y-11812D01*
Y-11844D01*
Y-11876D01*
Y-11908D01*
Y-11941D01*
Y-11973D01*
Y-12005D01*
Y-12037D01*
Y-12070D01*
Y-12102D01*
Y-12134D01*
Y-12167D01*
Y-12199D01*
Y-12231D01*
Y-12263D01*
Y-12296D01*
Y-12328D01*
Y-12360D01*
Y-12392D01*
Y-12425D01*
Y-12457D01*
Y-12489D01*
Y-12521D01*
D01*
Y-12554D01*
Y-12586D01*
Y-12618D01*
Y-12651D01*
Y-12683D01*
Y-12715D01*
Y-12747D01*
Y-12780D01*
Y-12812D01*
Y-12844D01*
Y-12876D01*
Y-12909D01*
Y-12941D01*
Y-12973D01*
Y-13005D01*
Y-13038D01*
Y-13070D01*
Y-13102D01*
Y-13134D01*
Y-13167D01*
Y-13199D01*
Y-13231D01*
Y-13263D01*
Y-13296D01*
Y-13328D01*
Y-13360D01*
Y-13393D01*
Y-13425D01*
Y-13457D01*
Y-13489D01*
Y-13522D01*
Y-13554D01*
Y-13586D01*
Y-13618D01*
Y-13651D01*
Y-13683D01*
Y-13715D01*
Y-13747D01*
Y-13780D01*
Y-13812D01*
Y-13844D01*
Y-13876D01*
Y-13909D01*
Y-13941D01*
Y-13973D01*
Y-14006D01*
Y-14038D01*
Y-14070D01*
Y-14102D01*
Y-14134D01*
Y-14167D01*
Y-14199D01*
Y-14231D01*
Y-14264D01*
Y-14296D01*
Y-14328D01*
Y-14360D01*
Y-14393D01*
Y-14425D01*
Y-14457D01*
Y-14489D01*
Y-14522D01*
Y-14554D01*
Y-14586D01*
Y-14618D01*
Y-14651D01*
Y-14683D01*
Y-14715D01*
Y-14748D01*
Y-14780D01*
Y-14812D01*
Y-14844D01*
Y-14877D01*
Y-14909D01*
Y-14941D01*
Y-14973D01*
Y-15006D01*
Y-15038D01*
Y-15070D01*
Y-15102D01*
Y-15135D01*
Y-15167D01*
Y-15199D01*
Y-15231D01*
Y-15264D01*
Y-15296D01*
Y-15328D01*
Y-15360D01*
Y-15393D01*
Y-15425D01*
Y-15457D01*
Y-15489D01*
Y-15522D01*
Y-15554D01*
Y-15586D01*
Y-15619D01*
Y-15651D01*
Y-15683D01*
Y-15715D01*
Y-15748D01*
Y-15780D01*
Y-15812D01*
Y-15844D01*
Y-15877D01*
Y-15909D01*
Y-15941D01*
Y-15973D01*
Y-16006D01*
Y-16038D01*
Y-16070D01*
Y-16103D01*
Y-16135D01*
Y-16167D01*
Y-16199D01*
Y-16232D01*
Y-16264D01*
Y-16296D01*
Y-16328D01*
Y-16361D01*
Y-16393D01*
Y-16425D01*
Y-16457D01*
Y-16490D01*
Y-16522D01*
Y-16554D01*
Y-16586D01*
Y-16619D01*
Y-16651D01*
Y-16683D01*
Y-16715D01*
Y-16748D01*
Y-16780D01*
Y-16812D01*
Y-16845D01*
Y-16877D01*
Y-16909D01*
Y-16941D01*
Y-16974D01*
Y-17006D01*
Y-17038D01*
Y-17070D01*
Y-17103D01*
Y-17135D01*
Y-17167D01*
Y-17199D01*
Y-17232D01*
Y-17264D01*
Y-17296D01*
Y-17328D01*
Y-17361D01*
Y-17393D01*
Y-17425D01*
Y-17458D01*
Y-17490D01*
Y-17522D01*
Y-17554D01*
Y-17586D01*
Y-17619D01*
Y-17651D01*
Y-17683D01*
Y-17716D01*
Y-17748D01*
Y-17780D01*
Y-17812D01*
Y-17845D01*
Y-17877D01*
Y-17909D01*
Y-17941D01*
Y-17974D01*
Y-18006D01*
Y-18038D01*
Y-18070D01*
Y-18103D01*
Y-18135D01*
Y-18167D01*
Y-18200D01*
Y-18232D01*
Y-18264D01*
Y-18296D01*
Y-18329D01*
Y-18361D01*
Y-18393D01*
Y-18425D01*
Y-18458D01*
Y-18490D01*
Y-18522D01*
Y-18554D01*
Y-18587D01*
Y-18619D01*
Y-18651D01*
Y-18683D01*
Y-18716D01*
Y-18748D01*
Y-18780D01*
Y-18812D01*
Y-18845D01*
Y-18877D01*
Y-18909D01*
Y-18941D01*
Y-18974D01*
Y-19006D01*
Y-19038D01*
Y-19071D01*
Y-19103D01*
Y-19135D01*
Y-19167D01*
Y-19200D01*
Y-19232D01*
Y-19264D01*
Y-19296D01*
Y-19329D01*
Y-19361D01*
Y-19393D01*
Y-19425D01*
Y-19458D01*
Y-19490D01*
Y-19522D01*
Y-19555D01*
Y-19587D01*
Y-19619D01*
Y-19651D01*
Y-19684D01*
Y-19716D01*
Y-19748D01*
Y-19780D01*
Y-19813D01*
Y-19845D01*
Y-19877D01*
Y-19909D01*
Y-19942D01*
Y-19974D01*
Y-20006D01*
Y-20039D01*
Y-20071D01*
Y-20103D01*
Y-20135D01*
Y-20167D01*
Y-20200D01*
Y-20232D01*
Y-20264D01*
Y-20297D01*
Y-20329D01*
Y-20361D01*
Y-20393D01*
Y-20426D01*
Y-20458D01*
Y-20490D01*
Y-20522D01*
Y-20555D01*
Y-20587D01*
Y-20619D01*
Y-20651D01*
Y-20684D01*
Y-20716D01*
Y-20748D01*
Y-20780D01*
Y-20813D01*
Y-20845D01*
Y-20877D01*
Y-20910D01*
Y-20942D01*
Y-20974D01*
Y-21006D01*
Y-21039D01*
Y-21071D01*
Y-21103D01*
Y-21135D01*
Y-21168D01*
Y-21200D01*
Y-21232D01*
Y-21264D01*
Y-21297D01*
Y-21329D01*
Y-21361D01*
Y-21393D01*
Y-21426D01*
Y-21458D01*
Y-21490D01*
Y-21522D01*
Y-21555D01*
Y-21587D01*
Y-21619D01*
Y-21652D01*
Y-21684D01*
Y-21716D01*
Y-21748D01*
Y-21781D01*
Y-21813D01*
Y-21845D01*
Y-21877D01*
Y-21910D01*
Y-21942D01*
Y-21974D01*
Y-22006D01*
Y-22039D01*
Y-22071D01*
Y-22103D01*
Y-22136D01*
Y-22168D01*
Y-22200D01*
Y-22232D01*
Y-22264D01*
Y-22297D01*
Y-22329D01*
Y-22361D01*
Y-22394D01*
X459469Y-22446D01*
X459459Y-22497D01*
X459442Y-22547D01*
X459419Y-22594D01*
X459390Y-22638D01*
X459355Y-22677D01*
X459316Y-22712D01*
X459272Y-22741D01*
X459225Y-22764D01*
X459176Y-22781D01*
X459124Y-22791D01*
X459072Y-22794D01*
X457878D01*
X457826Y-22791D01*
X457774Y-22781D01*
X457725Y-22764D01*
X457678Y-22741D01*
X457634Y-22712D01*
X457595Y-22677D01*
X457560Y-22638D01*
X457531Y-22594D01*
X457508Y-22547D01*
X457491Y-22497D01*
X457481Y-22446D01*
X457477Y-22394D01*
Y-22361D01*
Y-22329D01*
Y-22297D01*
Y-22264D01*
Y-22232D01*
Y-22200D01*
Y-22168D01*
Y-22136D01*
Y-22103D01*
Y-22071D01*
Y-22039D01*
Y-22006D01*
Y-21974D01*
Y-21942D01*
Y-21910D01*
Y-21877D01*
Y-21845D01*
Y-21813D01*
Y-21781D01*
Y-21748D01*
Y-21716D01*
Y-21684D01*
Y-21652D01*
Y-21619D01*
Y-21587D01*
Y-21555D01*
Y-21522D01*
Y-21490D01*
Y-21458D01*
Y-21426D01*
Y-21393D01*
Y-21361D01*
Y-21329D01*
Y-21297D01*
Y-21264D01*
Y-21232D01*
Y-21200D01*
Y-21168D01*
Y-21135D01*
Y-21103D01*
Y-21071D01*
Y-21039D01*
Y-21006D01*
Y-20974D01*
Y-20942D01*
Y-20910D01*
Y-20877D01*
Y-20845D01*
Y-20813D01*
Y-20780D01*
Y-20748D01*
Y-20716D01*
Y-20684D01*
Y-20651D01*
Y-20619D01*
Y-20587D01*
Y-20555D01*
Y-20522D01*
Y-20490D01*
Y-20458D01*
Y-20426D01*
Y-20393D01*
Y-20361D01*
Y-20329D01*
Y-20297D01*
Y-20264D01*
Y-20232D01*
Y-20200D01*
Y-20167D01*
Y-20135D01*
Y-20103D01*
Y-20071D01*
Y-20039D01*
Y-20006D01*
Y-19974D01*
Y-19942D01*
Y-19909D01*
Y-19877D01*
Y-19845D01*
Y-19813D01*
Y-19780D01*
Y-19748D01*
Y-19716D01*
Y-19684D01*
Y-19651D01*
Y-19619D01*
Y-19587D01*
Y-19555D01*
Y-19522D01*
Y-19490D01*
Y-19458D01*
Y-19425D01*
Y-19393D01*
Y-19361D01*
Y-19329D01*
Y-19296D01*
Y-19264D01*
Y-19232D01*
Y-19200D01*
Y-19167D01*
Y-19135D01*
Y-19103D01*
Y-19071D01*
Y-19038D01*
Y-19006D01*
Y-18974D01*
Y-18941D01*
Y-18909D01*
Y-18877D01*
Y-18845D01*
Y-18812D01*
Y-18780D01*
Y-18748D01*
Y-18716D01*
Y-18683D01*
Y-18651D01*
Y-18619D01*
Y-18587D01*
Y-18554D01*
Y-18522D01*
Y-18490D01*
Y-18458D01*
Y-18425D01*
Y-18393D01*
Y-18361D01*
Y-18329D01*
Y-18296D01*
Y-18264D01*
Y-18232D01*
Y-18200D01*
Y-18167D01*
Y-18135D01*
Y-18103D01*
Y-18070D01*
Y-18038D01*
Y-18006D01*
Y-17974D01*
Y-17941D01*
Y-17909D01*
Y-17877D01*
Y-17845D01*
Y-17812D01*
Y-17780D01*
Y-17748D01*
Y-17716D01*
Y-17683D01*
Y-17651D01*
Y-17619D01*
Y-17586D01*
Y-17554D01*
Y-17522D01*
Y-17490D01*
Y-17458D01*
Y-17425D01*
Y-17393D01*
Y-17361D01*
Y-17328D01*
Y-17296D01*
Y-17264D01*
Y-17232D01*
Y-17199D01*
Y-17167D01*
Y-17135D01*
Y-17103D01*
Y-17070D01*
Y-17038D01*
Y-17006D01*
Y-16974D01*
Y-16941D01*
Y-16909D01*
Y-16877D01*
Y-16845D01*
Y-16812D01*
Y-16780D01*
Y-16748D01*
Y-16715D01*
Y-16683D01*
Y-16651D01*
Y-16619D01*
Y-16586D01*
Y-16554D01*
Y-16522D01*
Y-16490D01*
Y-16457D01*
Y-16425D01*
Y-16393D01*
Y-16361D01*
Y-16328D01*
Y-16296D01*
Y-16264D01*
Y-16232D01*
Y-16199D01*
Y-16167D01*
Y-16135D01*
Y-16103D01*
Y-16070D01*
Y-16038D01*
Y-16006D01*
Y-15973D01*
Y-15941D01*
Y-15909D01*
Y-15877D01*
Y-15844D01*
Y-15812D01*
Y-15780D01*
Y-15748D01*
Y-15715D01*
Y-15683D01*
Y-15651D01*
Y-15619D01*
Y-15586D01*
Y-15554D01*
Y-15522D01*
Y-15489D01*
Y-15457D01*
Y-15425D01*
Y-15393D01*
Y-15360D01*
Y-15328D01*
Y-15296D01*
Y-15264D01*
Y-15231D01*
Y-15199D01*
Y-15167D01*
Y-15135D01*
Y-15102D01*
Y-15070D01*
Y-15038D01*
Y-15006D01*
Y-14973D01*
Y-14941D01*
Y-14909D01*
Y-14877D01*
Y-14844D01*
Y-14812D01*
Y-14780D01*
Y-14748D01*
Y-14715D01*
Y-14683D01*
Y-14651D01*
Y-14618D01*
Y-14586D01*
Y-14554D01*
Y-14522D01*
Y-14489D01*
Y-14457D01*
Y-14425D01*
Y-14393D01*
Y-14360D01*
Y-14328D01*
Y-14296D01*
Y-14264D01*
Y-14231D01*
Y-14199D01*
Y-14167D01*
Y-14134D01*
Y-14102D01*
Y-14070D01*
Y-14038D01*
Y-14006D01*
Y-13973D01*
Y-13941D01*
Y-13909D01*
Y-13876D01*
Y-13844D01*
Y-13812D01*
Y-13780D01*
Y-13747D01*
Y-13715D01*
Y-13683D01*
Y-13651D01*
Y-13618D01*
Y-13586D01*
Y-13554D01*
Y-13522D01*
Y-13489D01*
Y-13457D01*
Y-13425D01*
Y-13393D01*
Y-13360D01*
Y-13328D01*
Y-13296D01*
Y-13263D01*
Y-13231D01*
Y-13199D01*
Y-13167D01*
Y-13134D01*
Y-13102D01*
Y-13070D01*
Y-13038D01*
Y-13005D01*
Y-12973D01*
Y-12941D01*
Y-12909D01*
Y-12876D01*
Y-12844D01*
Y-12812D01*
Y-12780D01*
Y-12747D01*
Y-12715D01*
Y-12683D01*
Y-12651D01*
Y-12618D01*
Y-12586D01*
Y-12554D01*
Y-12521D01*
D01*
Y-12489D01*
Y-12457D01*
Y-12425D01*
Y-12392D01*
Y-12360D01*
Y-12328D01*
Y-12296D01*
Y-12263D01*
Y-12231D01*
Y-12199D01*
Y-12167D01*
Y-12134D01*
Y-12102D01*
Y-12070D01*
Y-12037D01*
Y-12005D01*
Y-11973D01*
Y-11941D01*
Y-11908D01*
Y-11876D01*
Y-11844D01*
Y-11812D01*
Y-11779D01*
Y-11747D01*
Y-11715D01*
Y-11683D01*
Y-11650D01*
Y-11618D01*
Y-11586D01*
Y-11554D01*
Y-11521D01*
Y-11489D01*
Y-11457D01*
Y-11425D01*
Y-11392D01*
Y-11360D01*
Y-11328D01*
Y-11295D01*
Y-11263D01*
Y-11231D01*
Y-11199D01*
Y-11167D01*
Y-11134D01*
Y-11102D01*
Y-11070D01*
Y-11037D01*
Y-11005D01*
Y-10973D01*
Y-10941D01*
Y-10908D01*
Y-10876D01*
Y-10844D01*
Y-10812D01*
Y-10779D01*
Y-10747D01*
Y-10715D01*
Y-10683D01*
Y-10650D01*
Y-10618D01*
Y-10586D01*
Y-10554D01*
Y-10521D01*
Y-10489D01*
Y-10457D01*
Y-10424D01*
Y-10392D01*
Y-10360D01*
Y-10328D01*
Y-10295D01*
Y-10263D01*
Y-10231D01*
Y-10199D01*
Y-10166D01*
Y-10134D01*
Y-10102D01*
Y-10069D01*
Y-10037D01*
Y-10005D01*
Y-9973D01*
Y-9940D01*
Y-9908D01*
Y-9876D01*
Y-9844D01*
Y-9811D01*
Y-9779D01*
Y-9747D01*
Y-9715D01*
Y-9682D01*
Y-9650D01*
Y-9618D01*
Y-9586D01*
Y-9553D01*
Y-9521D01*
Y-9489D01*
Y-9457D01*
Y-9424D01*
Y-9392D01*
Y-9360D01*
Y-9328D01*
Y-9295D01*
Y-9263D01*
Y-9231D01*
Y-9199D01*
Y-9166D01*
Y-9134D01*
Y-9102D01*
Y-9069D01*
Y-9037D01*
Y-9005D01*
Y-8973D01*
Y-8940D01*
Y-8908D01*
Y-8876D01*
Y-8844D01*
Y-8811D01*
Y-8779D01*
Y-8747D01*
Y-8715D01*
Y-8682D01*
Y-8650D01*
Y-8618D01*
Y-8585D01*
Y-8553D01*
Y-8521D01*
Y-8489D01*
Y-8456D01*
Y-8424D01*
Y-8392D01*
Y-8360D01*
Y-8327D01*
Y-8295D01*
Y-8263D01*
Y-8231D01*
Y-8198D01*
Y-8166D01*
Y-8134D01*
Y-8102D01*
Y-8069D01*
Y-8037D01*
Y-8005D01*
Y-7972D01*
Y-7940D01*
Y-7908D01*
Y-7876D01*
Y-7843D01*
Y-7811D01*
Y-7779D01*
Y-7747D01*
Y-7714D01*
Y-7682D01*
Y-7650D01*
Y-7618D01*
Y-7585D01*
Y-7553D01*
Y-7521D01*
Y-7489D01*
Y-7456D01*
Y-7424D01*
Y-7392D01*
Y-7360D01*
Y-7327D01*
Y-7295D01*
Y-7263D01*
Y-7231D01*
Y-7198D01*
Y-7166D01*
Y-7134D01*
Y-7102D01*
Y-7069D01*
Y-7037D01*
Y-7005D01*
Y-6972D01*
Y-6940D01*
Y-6908D01*
Y-6876D01*
Y-6843D01*
Y-6811D01*
Y-6779D01*
Y-6747D01*
Y-6714D01*
Y-6682D01*
Y-6650D01*
Y-6617D01*
Y-6585D01*
Y-6553D01*
Y-6521D01*
Y-6488D01*
Y-6456D01*
Y-6424D01*
Y-6392D01*
Y-6359D01*
Y-6327D01*
Y-6295D01*
Y-6263D01*
Y-6230D01*
Y-6198D01*
Y-6166D01*
Y-6134D01*
Y-6101D01*
Y-6069D01*
Y-6037D01*
Y-6005D01*
Y-5972D01*
Y-5940D01*
Y-5908D01*
Y-5875D01*
Y-5843D01*
Y-5811D01*
D01*
Y-5779D01*
Y-5746D01*
Y-5714D01*
Y-5682D01*
Y-5650D01*
Y-5617D01*
Y-5585D01*
Y-5553D01*
Y-5521D01*
Y-5488D01*
Y-5456D01*
Y-5424D01*
Y-5392D01*
Y-5359D01*
Y-5327D01*
Y-5295D01*
Y-5263D01*
Y-5230D01*
Y-5198D01*
Y-5166D01*
Y-5133D01*
Y-5101D01*
Y-5069D01*
Y-5037D01*
Y-5004D01*
Y-4972D01*
Y-4940D01*
Y-4908D01*
Y-4875D01*
Y-4843D01*
Y-4811D01*
Y-4779D01*
Y-4746D01*
Y-4714D01*
Y-4682D01*
Y-4650D01*
Y-4617D01*
Y-4585D01*
Y-4553D01*
Y-4521D01*
Y-4488D01*
Y-4456D01*
Y-4424D01*
Y-4391D01*
Y-4359D01*
Y-4327D01*
Y-4295D01*
Y-4262D01*
Y-4230D01*
Y-4198D01*
Y-4166D01*
Y-4133D01*
Y-4101D01*
Y-4069D01*
Y-4037D01*
Y-4004D01*
Y-3972D01*
Y-3940D01*
Y-3907D01*
Y-3875D01*
Y-3843D01*
Y-3811D01*
Y-3779D01*
Y-3746D01*
Y-3714D01*
Y-3682D01*
Y-3650D01*
Y-3617D01*
Y-3585D01*
Y-3553D01*
Y-3520D01*
Y-3488D01*
Y-3456D01*
Y-3424D01*
Y-3391D01*
Y-3359D01*
Y-3327D01*
Y-3295D01*
Y-3262D01*
Y-3230D01*
Y-3198D01*
Y-3165D01*
Y-3133D01*
Y-3101D01*
Y-3069D01*
Y-3036D01*
Y-3004D01*
Y-2972D01*
Y-2940D01*
Y-2907D01*
Y-2875D01*
Y-2843D01*
Y-2811D01*
Y-2778D01*
Y-2746D01*
Y-2714D01*
Y-2682D01*
Y-2649D01*
Y-2617D01*
Y-2585D01*
Y-2553D01*
Y-2520D01*
Y-2488D01*
Y-2456D01*
Y-2424D01*
Y-2391D01*
Y-2359D01*
Y-2327D01*
Y-2294D01*
Y-2262D01*
Y-2230D01*
Y-2198D01*
Y-2165D01*
Y-2133D01*
Y-2101D01*
Y-2069D01*
Y-2036D01*
Y-2004D01*
Y-1972D01*
Y-1940D01*
Y-1907D01*
Y-1875D01*
Y-1843D01*
Y-1811D01*
Y-1778D01*
Y-1746D01*
Y-1714D01*
Y-1681D01*
Y-1649D01*
Y-1617D01*
Y-1585D01*
Y-1552D01*
Y-1520D01*
Y-1488D01*
Y-1456D01*
Y-1423D01*
Y-1391D01*
Y-1359D01*
Y-1327D01*
Y-1294D01*
Y-1262D01*
Y-1230D01*
Y-1198D01*
Y-1165D01*
Y-1133D01*
Y-1101D01*
Y-1068D01*
Y-1036D01*
Y-1004D01*
Y-972D01*
Y-939D01*
Y-907D01*
Y-875D01*
Y-843D01*
Y-810D01*
Y-778D01*
Y-746D01*
Y-714D01*
Y-681D01*
Y-649D01*
Y-617D01*
Y-585D01*
Y-552D01*
Y-520D01*
Y-488D01*
Y-455D01*
Y-423D01*
Y-391D01*
Y-359D01*
Y-326D01*
Y-294D01*
Y-262D01*
Y-230D01*
Y-197D01*
Y-165D01*
Y-133D01*
Y-101D01*
Y-68D01*
Y-36D01*
Y-4D01*
Y28D01*
Y61D01*
Y93D01*
Y125D01*
Y157D01*
Y190D01*
Y222D01*
Y254D01*
Y286D01*
Y319D01*
Y351D01*
Y383D01*
Y416D01*
Y448D01*
Y480D01*
Y512D01*
Y545D01*
Y577D01*
Y609D01*
Y641D01*
Y674D01*
Y706D01*
Y738D01*
Y770D01*
Y803D01*
Y835D01*
Y867D01*
Y900D01*
Y932D01*
Y964D01*
Y996D01*
Y1029D01*
Y1061D01*
Y1093D01*
Y1125D01*
Y1158D01*
Y1190D01*
Y1222D01*
Y1254D01*
Y1287D01*
Y1319D01*
Y1351D01*
Y1383D01*
Y1416D01*
Y1448D01*
Y1480D01*
Y1512D01*
Y1545D01*
Y1577D01*
Y1609D01*
Y1641D01*
Y1674D01*
Y1706D01*
Y1738D01*
Y1770D01*
Y1803D01*
Y1835D01*
Y1867D01*
Y1900D01*
Y1932D01*
Y1964D01*
Y1996D01*
Y2029D01*
Y2061D01*
Y2093D01*
Y2125D01*
Y2158D01*
Y2190D01*
Y2222D01*
Y2254D01*
Y2287D01*
Y2319D01*
Y2351D01*
Y2383D01*
Y2416D01*
Y2448D01*
Y2480D01*
Y2513D01*
Y2545D01*
Y2577D01*
Y2609D01*
Y2642D01*
Y2674D01*
Y2706D01*
Y2738D01*
Y2771D01*
Y2803D01*
Y2835D01*
Y2867D01*
Y2900D01*
Y2932D01*
Y2964D01*
Y2997D01*
Y3029D01*
Y3061D01*
Y3093D01*
Y3125D01*
Y3158D01*
Y3190D01*
Y3222D01*
Y3255D01*
Y3287D01*
Y3319D01*
Y3351D01*
Y3384D01*
Y3416D01*
Y3448D01*
Y3480D01*
Y3513D01*
Y3545D01*
Y3577D01*
Y3609D01*
Y3642D01*
Y3674D01*
Y3706D01*
Y3739D01*
Y3771D01*
Y3803D01*
Y3835D01*
Y3867D01*
Y3900D01*
Y3932D01*
Y3964D01*
Y3997D01*
Y4029D01*
Y4061D01*
Y4093D01*
Y4126D01*
Y4158D01*
Y4190D01*
Y4222D01*
Y4255D01*
Y4287D01*
Y4319D01*
Y4352D01*
Y4384D01*
Y4416D01*
Y4448D01*
Y4481D01*
Y4513D01*
Y4545D01*
Y4577D01*
Y4610D01*
Y4642D01*
Y4674D01*
Y4706D01*
Y4739D01*
Y4771D01*
Y4803D01*
Y4835D01*
Y4868D01*
Y4900D01*
Y4932D01*
Y4964D01*
Y4997D01*
Y5029D01*
Y5061D01*
Y5094D01*
D01*
Y5126D01*
Y5158D01*
Y5190D01*
Y5223D01*
Y5255D01*
Y5287D01*
Y5319D01*
Y5352D01*
Y5384D01*
Y5416D01*
Y5448D01*
Y5481D01*
Y5513D01*
Y5545D01*
Y5577D01*
Y5610D01*
Y5642D01*
Y5674D01*
Y5706D01*
Y5739D01*
Y5771D01*
Y5803D01*
Y5835D01*
Y5868D01*
Y5900D01*
Y5932D01*
Y5965D01*
Y5997D01*
Y6029D01*
Y6061D01*
Y6094D01*
Y6126D01*
Y6158D01*
Y6190D01*
Y6223D01*
Y6255D01*
Y6287D01*
Y6319D01*
Y6352D01*
Y6384D01*
Y6416D01*
Y6448D01*
Y6481D01*
Y6513D01*
Y6545D01*
Y6577D01*
Y6610D01*
Y6642D01*
Y6674D01*
Y6707D01*
Y6739D01*
Y6771D01*
Y6803D01*
Y6836D01*
Y6868D01*
Y6900D01*
Y6932D01*
Y6965D01*
Y6997D01*
Y7029D01*
Y7062D01*
Y7094D01*
Y7126D01*
Y7158D01*
Y7191D01*
Y7223D01*
Y7255D01*
Y7287D01*
Y7320D01*
Y7352D01*
Y7384D01*
Y7416D01*
Y7449D01*
Y7481D01*
Y7513D01*
Y7545D01*
Y7578D01*
Y7610D01*
Y7642D01*
Y7674D01*
Y7707D01*
Y7739D01*
Y7771D01*
Y7803D01*
Y7836D01*
Y7868D01*
Y7900D01*
Y7932D01*
Y7965D01*
Y7997D01*
Y8029D01*
Y8062D01*
Y8094D01*
Y8126D01*
Y8158D01*
Y8191D01*
Y8223D01*
Y8255D01*
Y8287D01*
Y8320D01*
Y8352D01*
Y8384D01*
Y8416D01*
Y8449D01*
Y8481D01*
Y8513D01*
Y8546D01*
Y8578D01*
Y8610D01*
Y8642D01*
Y8675D01*
Y8707D01*
Y8739D01*
Y8771D01*
Y8804D01*
Y8836D01*
Y8868D01*
Y8900D01*
Y8933D01*
Y8965D01*
Y8997D01*
Y9029D01*
Y9062D01*
Y9094D01*
Y9126D01*
Y9159D01*
Y9191D01*
Y9223D01*
Y9255D01*
Y9287D01*
Y9320D01*
Y9352D01*
Y9384D01*
Y9417D01*
Y9449D01*
Y9481D01*
Y9513D01*
Y9546D01*
Y9578D01*
Y9610D01*
Y9642D01*
Y9675D01*
Y9707D01*
Y9739D01*
Y9771D01*
Y9804D01*
Y9836D01*
Y9868D01*
Y9900D01*
Y9933D01*
Y9965D01*
Y9997D01*
Y10029D01*
Y10062D01*
Y10094D01*
Y10126D01*
Y10159D01*
Y10191D01*
Y10223D01*
Y10255D01*
Y10288D01*
Y10320D01*
Y10352D01*
Y10384D01*
Y10417D01*
Y10449D01*
Y10481D01*
Y10514D01*
Y10546D01*
Y10578D01*
Y10610D01*
Y10643D01*
Y10675D01*
Y10707D01*
Y10739D01*
Y10772D01*
Y10804D01*
Y10836D01*
Y10868D01*
Y10901D01*
Y10933D01*
Y10965D01*
Y10997D01*
Y11030D01*
Y11062D01*
Y11094D01*
Y11126D01*
Y11159D01*
Y11191D01*
Y11223D01*
Y11255D01*
Y11288D01*
Y11320D01*
Y11352D01*
Y11384D01*
Y11417D01*
Y11449D01*
Y11481D01*
Y11514D01*
Y11546D01*
Y11578D01*
Y11610D01*
Y11643D01*
Y11675D01*
Y11707D01*
Y11739D01*
Y11772D01*
Y11804D01*
Y11836D01*
Y11868D01*
Y11901D01*
Y11933D01*
Y11965D01*
Y11998D01*
Y12030D01*
Y12062D01*
Y12094D01*
Y12127D01*
Y12159D01*
Y12191D01*
Y12223D01*
Y12256D01*
Y12288D01*
Y12320D01*
Y12352D01*
Y12357D01*
X457476Y12360D01*
X457459Y12410D01*
X457449Y12461D01*
X457445Y12514D01*
Y12518D01*
X457443Y12522D01*
X457441Y12530D01*
X457434Y12539D01*
X457411Y12586D01*
X457408Y12594D01*
X457402Y12604D01*
X457399Y12610D01*
X457388Y12633D01*
X457367Y12657D01*
X457338Y12700D01*
X457333Y12710D01*
X457323Y12715D01*
X457279Y12744D01*
X457256Y12765D01*
X457226Y12779D01*
X457217Y12786D01*
X457209Y12789D01*
X457162Y12812D01*
X457152Y12818D01*
X457144Y12821D01*
X457136Y12825D01*
X457116Y12826D01*
X457065Y12836D01*
X457015Y12853D01*
X457012Y12855D01*
X453071D01*
X453019Y12858D01*
X452968Y12868D01*
X452918Y12885D01*
X452871Y12909D01*
X452827Y12938D01*
X452788Y12972D01*
X452753Y13012D01*
X452724Y13055D01*
X452701Y13102D01*
X452684Y13152D01*
X452674Y13203D01*
X452670Y13256D01*
Y13288D01*
Y13320D01*
Y13352D01*
Y13385D01*
Y13417D01*
Y13449D01*
Y13482D01*
Y13514D01*
Y13546D01*
Y13578D01*
Y13611D01*
Y13643D01*
Y13675D01*
Y13707D01*
Y13740D01*
Y13772D01*
Y13804D01*
Y13836D01*
Y13869D01*
Y13901D01*
Y13933D01*
Y13965D01*
Y13998D01*
Y14030D01*
Y14062D01*
Y14095D01*
Y14127D01*
Y14159D01*
Y14191D01*
Y14224D01*
Y14256D01*
Y14288D01*
Y14320D01*
Y14353D01*
Y14385D01*
Y14417D01*
Y14449D01*
Y14482D01*
X452674Y14534D01*
X452684Y14585D01*
X452701Y14635D01*
X452724Y14682D01*
X452753Y14726D01*
X452788Y14765D01*
X452827Y14800D01*
X452871Y14829D01*
X452918Y14852D01*
X452968Y14869D01*
X453019Y14879D01*
X453071Y14883D01*
X457168D01*
X457221Y14879D01*
D02*
G37*
G36*
X58465Y-23228D02*
X56693D01*
X54921Y-21457D01*
Y-19291D01*
X58465D01*
Y-23228D01*
D02*
G37*
G36*
X187008Y-98228D02*
X186221D01*
Y-96457D01*
X185433D01*
Y-95866D01*
X187008D01*
Y-98228D01*
D02*
G37*
G36*
X429331Y-143898D02*
Y-146063D01*
X425787D01*
Y-142126D01*
X427559D01*
X429331Y-143898D01*
D02*
G37*
G36*
X279134Y-199016D02*
X278346D01*
Y-197244D01*
X277559D01*
Y-196653D01*
X279134D01*
Y-199016D01*
D02*
G37*
G36*
X324213Y-237008D02*
X321850D01*
Y-236221D01*
X323622D01*
Y-235433D01*
X324213D01*
Y-237008D01*
D02*
G37*
G36*
X478937Y-262992D02*
X476575D01*
Y-262205D01*
X478346D01*
Y-261417D01*
X478937D01*
Y-262992D01*
D02*
G37*
G36*
X337992Y-290158D02*
X335630D01*
Y-289370D01*
X337402D01*
Y-288583D01*
X337992D01*
Y-290158D01*
D02*
G37*
G36*
X319094Y-290945D02*
X316732D01*
Y-290158D01*
X318504D01*
Y-289370D01*
X319094D01*
Y-290945D01*
D02*
G37*
G36*
X237992Y-343110D02*
X38189D01*
Y-143307D01*
X237992D01*
Y-343110D01*
D02*
G37*
%LPC*%
G36*
X462994Y1176D02*
X462456D01*
X462469Y1164D01*
X462499Y1150D01*
X462542Y1121D01*
X462566Y1100D01*
X462594Y1086D01*
X462595Y1085D01*
X462639Y1056D01*
X462678Y1022D01*
X462694Y1004D01*
X462711Y989D01*
X462726Y972D01*
X462740Y959D01*
X462743Y957D01*
X462758Y940D01*
X462775Y925D01*
X462790Y908D01*
X462807Y893D01*
X462823Y875D01*
X462840Y860D01*
X462874Y821D01*
X462903Y777D01*
X462918Y748D01*
X462939Y724D01*
X462968Y680D01*
X462982Y651D01*
X462994Y638D01*
Y641D01*
Y674D01*
Y706D01*
Y738D01*
Y770D01*
Y803D01*
Y835D01*
Y867D01*
Y900D01*
Y932D01*
Y964D01*
Y996D01*
Y1029D01*
Y1061D01*
Y1093D01*
Y1125D01*
Y1158D01*
Y1176D01*
D02*
G37*
G36*
X486563Y6209D02*
X483103D01*
X483099Y6207D01*
X483049Y6190D01*
X482998Y6180D01*
X482946Y6177D01*
X482941D01*
X482938Y6175D01*
X482888Y6158D01*
X482862Y6153D01*
X482859Y6151D01*
X482857Y6150D01*
X482843Y6134D01*
X482842Y6133D01*
X482825Y6118D01*
X482810Y6101D01*
X482793Y6086D01*
X482779Y6070D01*
X482778Y6068D01*
X482760Y6053D01*
X482745Y6036D01*
X482728Y6021D01*
X482713Y6004D01*
X482696Y5989D01*
X482682Y5973D01*
X482681Y5971D01*
X482664Y5957D01*
X482648Y5939D01*
X482631Y5924D01*
X482616Y5907D01*
X482599Y5892D01*
X482584Y5875D01*
X482567Y5860D01*
X482552Y5842D01*
X482534Y5827D01*
X482519Y5810D01*
X482502Y5795D01*
X482487Y5778D01*
X482470Y5763D01*
X482455Y5746D01*
X482438Y5731D01*
X482423Y5713D01*
X482405Y5698D01*
X482390Y5681D01*
X482373Y5666D01*
X482358Y5649D01*
X482341Y5634D01*
X482326Y5617D01*
X482309Y5601D01*
X482294Y5584D01*
X482276Y5569D01*
X482261Y5552D01*
X482244Y5537D01*
X482229Y5520D01*
X482212Y5505D01*
X482197Y5488D01*
X482180Y5472D01*
X482164Y5455D01*
X482147Y5440D01*
X482132Y5423D01*
X482115Y5408D01*
X482100Y5391D01*
X482083Y5376D01*
X482069Y5360D01*
X482058Y5327D01*
X482056Y5324D01*
Y5319D01*
X482053Y5267D01*
X482042Y5216D01*
X482026Y5166D01*
X482024Y5162D01*
Y5158D01*
Y5126D01*
Y5094D01*
Y5061D01*
Y5029D01*
Y4997D01*
Y4964D01*
Y4932D01*
Y4900D01*
Y4868D01*
Y4835D01*
Y4803D01*
Y4771D01*
Y4739D01*
Y4706D01*
Y4674D01*
Y4642D01*
Y4610D01*
Y4577D01*
Y4545D01*
Y4513D01*
Y4481D01*
Y4448D01*
Y4416D01*
Y4384D01*
Y4352D01*
Y4319D01*
Y4287D01*
Y4255D01*
Y4222D01*
Y4190D01*
Y4158D01*
Y4126D01*
Y4093D01*
Y4061D01*
Y4029D01*
Y3997D01*
Y3964D01*
Y3932D01*
Y3900D01*
Y3867D01*
Y3835D01*
Y3803D01*
Y3771D01*
Y3739D01*
Y3706D01*
Y3674D01*
Y3642D01*
Y3609D01*
Y3577D01*
Y3545D01*
Y3513D01*
Y3480D01*
Y3448D01*
Y3416D01*
Y3384D01*
Y3351D01*
Y3319D01*
Y3287D01*
Y3255D01*
Y3222D01*
Y3190D01*
Y3158D01*
Y3125D01*
Y3093D01*
Y3061D01*
Y3029D01*
Y2997D01*
Y2964D01*
Y2932D01*
Y2900D01*
Y2867D01*
Y2835D01*
Y2803D01*
Y2771D01*
Y2738D01*
Y2706D01*
Y2674D01*
Y2642D01*
Y2609D01*
Y2577D01*
Y2545D01*
Y2513D01*
Y2480D01*
Y2448D01*
Y2416D01*
Y2383D01*
Y2351D01*
Y2319D01*
Y2287D01*
Y2254D01*
Y2222D01*
Y2190D01*
Y2158D01*
Y2125D01*
Y2093D01*
Y2061D01*
Y2029D01*
Y1996D01*
Y1964D01*
Y1932D01*
Y1900D01*
Y1867D01*
Y1835D01*
Y1803D01*
Y1770D01*
Y1738D01*
Y1706D01*
Y1674D01*
Y1641D01*
Y1609D01*
Y1577D01*
Y1545D01*
Y1512D01*
Y1480D01*
Y1448D01*
Y1416D01*
Y1383D01*
Y1351D01*
Y1319D01*
Y1287D01*
Y1254D01*
Y1222D01*
Y1190D01*
Y1158D01*
Y1125D01*
Y1093D01*
Y1061D01*
Y1029D01*
Y996D01*
Y992D01*
X482026Y988D01*
X482042Y939D01*
X482053Y887D01*
X482056Y835D01*
Y831D01*
X482058Y827D01*
X482060Y819D01*
X482067Y809D01*
X482081Y780D01*
X482083Y779D01*
X482100Y764D01*
X482115Y746D01*
X482132Y731D01*
X482147Y714D01*
X482164Y699D01*
X482180Y682D01*
X482197Y667D01*
X482212Y649D01*
X482229Y634D01*
X482244Y617D01*
X482261Y602D01*
X482276Y585D01*
X482294Y570D01*
X482309Y553D01*
X482326Y538D01*
X482341Y520D01*
X482341Y520D01*
X482358Y505D01*
X482373Y488D01*
X482390Y473D01*
X482405Y456D01*
X482423Y441D01*
X482438Y424D01*
X482455Y409D01*
X482470Y391D01*
X482470Y391D01*
X482487Y376D01*
X482502Y359D01*
X482519Y344D01*
X482534Y327D01*
X482552Y312D01*
X482567Y295D01*
X482584Y280D01*
X482599Y262D01*
X482616Y247D01*
X482631Y230D01*
X482648Y215D01*
X482664Y198D01*
X482681Y183D01*
X482696Y166D01*
X482713Y151D01*
X482728Y133D01*
X482745Y118D01*
X482760Y101D01*
X482778Y86D01*
X482793Y69D01*
X482810Y54D01*
X482825Y37D01*
X482842Y21D01*
X482854Y7D01*
X482869Y6D01*
X482920Y-4D01*
X482970Y-21D01*
X482974Y-22D01*
X486610D01*
Y-4D01*
Y28D01*
Y61D01*
Y93D01*
Y125D01*
Y157D01*
Y190D01*
Y222D01*
Y254D01*
Y286D01*
Y319D01*
Y351D01*
Y383D01*
Y416D01*
Y448D01*
Y480D01*
Y512D01*
Y545D01*
Y577D01*
Y609D01*
Y641D01*
Y674D01*
Y706D01*
Y738D01*
Y770D01*
Y803D01*
Y821D01*
X483430D01*
X483377Y825D01*
X483326Y835D01*
X483276Y852D01*
X483229Y875D01*
X483186Y904D01*
X483146Y939D01*
X483131Y956D01*
X483114Y971D01*
X483079Y1010D01*
X483050Y1054D01*
X483027Y1101D01*
X483010Y1151D01*
X483000Y1202D01*
X482997Y1254D01*
Y1287D01*
Y1319D01*
Y1351D01*
Y1383D01*
Y1416D01*
Y1448D01*
Y1480D01*
Y1512D01*
Y1545D01*
Y1577D01*
Y1609D01*
Y1641D01*
Y1674D01*
Y1706D01*
Y1738D01*
Y1770D01*
Y1803D01*
Y1835D01*
Y1867D01*
Y1900D01*
Y1932D01*
Y1964D01*
Y1996D01*
Y2029D01*
Y2061D01*
Y2093D01*
Y2125D01*
Y2158D01*
Y2190D01*
Y2222D01*
Y2254D01*
Y2287D01*
Y2319D01*
Y2351D01*
X483000Y2403D01*
X483010Y2455D01*
X483027Y2505D01*
X483050Y2552D01*
X483079Y2595D01*
X483114Y2635D01*
X483131Y2650D01*
X483146Y2667D01*
X483186Y2702D01*
X483229Y2731D01*
X483276Y2754D01*
X483326Y2771D01*
X483377Y2781D01*
X483430Y2784D01*
X486094D01*
Y2803D01*
Y2835D01*
Y2867D01*
Y2900D01*
Y2932D01*
Y2964D01*
Y2997D01*
Y3029D01*
Y3061D01*
Y3093D01*
Y3125D01*
Y3158D01*
Y3190D01*
Y3222D01*
Y3255D01*
Y3287D01*
Y3319D01*
Y3351D01*
Y3370D01*
X483430D01*
X483377Y3373D01*
X483326Y3384D01*
X483276Y3400D01*
X483229Y3424D01*
X483186Y3453D01*
X483146Y3487D01*
X483131Y3505D01*
X483114Y3520D01*
X483079Y3559D01*
X483050Y3603D01*
X483027Y3650D01*
X483010Y3699D01*
X483000Y3751D01*
X482997Y3803D01*
Y3835D01*
Y3867D01*
Y3900D01*
Y3932D01*
Y3964D01*
Y3997D01*
Y4029D01*
Y4061D01*
Y4093D01*
Y4126D01*
Y4158D01*
Y4190D01*
Y4222D01*
Y4255D01*
Y4287D01*
Y4319D01*
Y4352D01*
Y4384D01*
Y4416D01*
Y4448D01*
Y4481D01*
Y4513D01*
Y4545D01*
Y4577D01*
Y4610D01*
Y4642D01*
Y4674D01*
Y4706D01*
Y4739D01*
Y4771D01*
Y4803D01*
Y4835D01*
Y4868D01*
Y4900D01*
Y4932D01*
X483000Y4984D01*
X483010Y5036D01*
X483027Y5086D01*
X483050Y5133D01*
X483079Y5176D01*
X483114Y5216D01*
X483130Y5229D01*
X483131Y5231D01*
X483146Y5248D01*
X483186Y5283D01*
X483229Y5312D01*
X483276Y5335D01*
X483326Y5352D01*
X483377Y5362D01*
X483430Y5365D01*
X486610D01*
Y5384D01*
Y5416D01*
Y5448D01*
Y5481D01*
Y5513D01*
Y5545D01*
Y5577D01*
Y5610D01*
Y5642D01*
Y5674D01*
Y5706D01*
Y5739D01*
Y5771D01*
Y5803D01*
Y5835D01*
Y5868D01*
Y5900D01*
Y5932D01*
Y5965D01*
Y5997D01*
Y6029D01*
Y6061D01*
Y6094D01*
Y6126D01*
Y6158D01*
Y6190D01*
Y6193D01*
X486567Y6207D01*
X486563Y6209D01*
D02*
G37*
G36*
X478157D02*
X473862D01*
Y6190D01*
Y6158D01*
Y6126D01*
Y6094D01*
Y6061D01*
Y6029D01*
Y5997D01*
Y5965D01*
Y5932D01*
Y5900D01*
Y5868D01*
Y5835D01*
Y5803D01*
Y5771D01*
Y5739D01*
Y5706D01*
Y5674D01*
Y5642D01*
Y5610D01*
Y5577D01*
Y5545D01*
Y5513D01*
Y5481D01*
Y5448D01*
Y5416D01*
Y5384D01*
Y5352D01*
Y5319D01*
Y5287D01*
Y5255D01*
Y5223D01*
Y5190D01*
Y5158D01*
Y5126D01*
Y5094D01*
Y5061D01*
Y5029D01*
Y4997D01*
Y4964D01*
Y4932D01*
Y4900D01*
Y4868D01*
Y4835D01*
Y4803D01*
Y4771D01*
Y4739D01*
Y4706D01*
Y4674D01*
Y4642D01*
Y4610D01*
Y4577D01*
Y4545D01*
Y4513D01*
Y4481D01*
Y4448D01*
Y4416D01*
Y4384D01*
Y4352D01*
Y4319D01*
Y4287D01*
Y4255D01*
Y4222D01*
Y4190D01*
Y4158D01*
Y4126D01*
Y4093D01*
Y4061D01*
Y4029D01*
Y3997D01*
Y3964D01*
Y3932D01*
Y3900D01*
Y3867D01*
Y3835D01*
Y3803D01*
Y3771D01*
Y3739D01*
Y3706D01*
Y3674D01*
Y3642D01*
Y3609D01*
Y3577D01*
Y3545D01*
Y3513D01*
Y3480D01*
Y3448D01*
Y3416D01*
Y3384D01*
Y3351D01*
Y3319D01*
Y3287D01*
Y3255D01*
Y3222D01*
Y3190D01*
Y3158D01*
Y3125D01*
Y3093D01*
Y3061D01*
Y3029D01*
Y2997D01*
Y2964D01*
Y2932D01*
Y2900D01*
Y2867D01*
Y2835D01*
Y2803D01*
Y2771D01*
Y2738D01*
Y2706D01*
Y2674D01*
Y2642D01*
Y2609D01*
Y2577D01*
Y2545D01*
Y2513D01*
Y2480D01*
Y2448D01*
Y2416D01*
Y2383D01*
Y2351D01*
Y2319D01*
Y2287D01*
Y2254D01*
Y2222D01*
Y2190D01*
Y2158D01*
Y2125D01*
Y2093D01*
Y2061D01*
Y2029D01*
Y1996D01*
Y1964D01*
Y1932D01*
Y1900D01*
Y1867D01*
Y1835D01*
Y1803D01*
Y1770D01*
Y1738D01*
Y1706D01*
Y1674D01*
Y1641D01*
Y1609D01*
Y1577D01*
Y1545D01*
Y1512D01*
Y1480D01*
Y1448D01*
Y1416D01*
Y1383D01*
Y1351D01*
Y1319D01*
Y1287D01*
Y1254D01*
Y1222D01*
Y1190D01*
Y1158D01*
Y1125D01*
Y1093D01*
Y1061D01*
Y1029D01*
Y996D01*
Y964D01*
Y932D01*
Y900D01*
Y867D01*
Y835D01*
Y803D01*
Y770D01*
Y738D01*
Y706D01*
Y674D01*
Y641D01*
Y609D01*
Y577D01*
Y545D01*
Y512D01*
Y480D01*
Y448D01*
Y416D01*
Y383D01*
Y351D01*
Y319D01*
Y286D01*
Y254D01*
Y222D01*
Y190D01*
Y157D01*
Y125D01*
Y93D01*
Y61D01*
Y28D01*
Y-4D01*
Y-22D01*
X474834D01*
Y-4D01*
Y28D01*
Y61D01*
Y93D01*
Y125D01*
Y157D01*
Y190D01*
Y222D01*
Y254D01*
Y286D01*
Y319D01*
Y351D01*
Y383D01*
Y416D01*
Y448D01*
Y480D01*
Y512D01*
Y545D01*
Y577D01*
Y609D01*
Y641D01*
Y674D01*
Y706D01*
Y738D01*
Y770D01*
Y803D01*
Y835D01*
Y867D01*
Y900D01*
Y932D01*
Y964D01*
Y996D01*
Y1029D01*
Y1061D01*
Y1093D01*
Y1125D01*
Y1158D01*
Y1190D01*
Y1222D01*
Y1254D01*
Y1287D01*
Y1319D01*
Y1351D01*
Y1383D01*
Y1416D01*
Y1448D01*
Y1480D01*
Y1512D01*
Y1545D01*
Y1577D01*
Y1609D01*
Y1641D01*
Y1674D01*
Y1706D01*
Y1738D01*
Y1770D01*
Y1803D01*
Y1835D01*
Y1867D01*
Y1900D01*
Y1932D01*
Y1964D01*
Y1996D01*
Y2029D01*
Y2061D01*
Y2093D01*
Y2125D01*
Y2158D01*
Y2190D01*
Y2222D01*
Y2254D01*
Y2287D01*
Y2319D01*
Y2351D01*
Y2383D01*
Y2416D01*
Y2448D01*
Y2480D01*
Y2513D01*
Y2545D01*
Y2577D01*
Y2609D01*
Y2642D01*
Y2674D01*
Y2706D01*
Y2738D01*
Y2771D01*
Y2803D01*
Y2835D01*
Y2867D01*
Y2900D01*
Y2932D01*
Y2964D01*
Y2997D01*
Y3029D01*
Y3061D01*
Y3093D01*
Y3125D01*
Y3158D01*
Y3190D01*
Y3222D01*
Y3255D01*
Y3287D01*
Y3319D01*
Y3351D01*
Y3384D01*
Y3416D01*
Y3448D01*
Y3480D01*
Y3513D01*
Y3545D01*
Y3577D01*
Y3609D01*
Y3642D01*
Y3674D01*
Y3706D01*
Y3739D01*
Y3771D01*
Y3803D01*
Y3835D01*
Y3867D01*
Y3900D01*
Y3932D01*
Y3964D01*
Y3997D01*
Y4029D01*
Y4061D01*
Y4093D01*
Y4126D01*
Y4158D01*
Y4190D01*
Y4222D01*
Y4255D01*
Y4287D01*
Y4319D01*
Y4352D01*
Y4384D01*
Y4416D01*
Y4448D01*
Y4481D01*
Y4513D01*
Y4545D01*
Y4577D01*
Y4610D01*
Y4642D01*
Y4674D01*
Y4706D01*
Y4739D01*
Y4771D01*
Y4803D01*
Y4835D01*
Y4868D01*
X474838Y4920D01*
X474848Y4971D01*
X474865Y5021D01*
X474888Y5068D01*
X474917Y5112D01*
X474952Y5151D01*
X474991Y5186D01*
X475035Y5215D01*
X475082Y5238D01*
X475131Y5255D01*
X475183Y5265D01*
X475235Y5269D01*
X476332D01*
X476384Y5265D01*
X476436Y5255D01*
X476485Y5238D01*
X476533Y5215D01*
X476576Y5186D01*
X476615Y5151D01*
X476650Y5112D01*
X476679Y5068D01*
X476702Y5021D01*
X476719Y4971D01*
X476729Y4920D01*
X476733Y4868D01*
Y4835D01*
Y4803D01*
Y4771D01*
Y4739D01*
Y4706D01*
Y4674D01*
Y4642D01*
Y4610D01*
Y4577D01*
Y4545D01*
Y4513D01*
Y4481D01*
Y4448D01*
Y4416D01*
Y4384D01*
Y4352D01*
Y4319D01*
Y4287D01*
Y4255D01*
Y4222D01*
Y4190D01*
Y4158D01*
Y4126D01*
Y4093D01*
Y4061D01*
Y4029D01*
Y3997D01*
Y3964D01*
Y3932D01*
Y3900D01*
Y3867D01*
Y3835D01*
Y3803D01*
Y3771D01*
Y3739D01*
Y3706D01*
Y3674D01*
Y3642D01*
Y3609D01*
Y3577D01*
Y3545D01*
Y3513D01*
Y3480D01*
Y3448D01*
Y3416D01*
Y3384D01*
Y3351D01*
Y3319D01*
Y3287D01*
Y3255D01*
Y3222D01*
Y3190D01*
Y3158D01*
Y3125D01*
Y3093D01*
Y3061D01*
Y3029D01*
Y2997D01*
Y2964D01*
Y2932D01*
Y2900D01*
Y2867D01*
Y2835D01*
Y2803D01*
Y2771D01*
Y2738D01*
Y2706D01*
Y2674D01*
Y2642D01*
Y2609D01*
Y2577D01*
Y2545D01*
Y2513D01*
Y2480D01*
Y2448D01*
Y2416D01*
Y2383D01*
Y2351D01*
Y2319D01*
Y2287D01*
Y2254D01*
Y2222D01*
Y2190D01*
Y2158D01*
Y2125D01*
Y2093D01*
Y2061D01*
Y2029D01*
Y1996D01*
Y1964D01*
Y1932D01*
Y1900D01*
Y1867D01*
Y1835D01*
Y1803D01*
Y1770D01*
Y1738D01*
Y1706D01*
Y1674D01*
Y1641D01*
Y1609D01*
Y1577D01*
Y1545D01*
Y1512D01*
Y1480D01*
Y1448D01*
Y1416D01*
Y1383D01*
Y1351D01*
Y1319D01*
Y1287D01*
Y1254D01*
Y1222D01*
Y1190D01*
Y1158D01*
Y1125D01*
Y1093D01*
Y1061D01*
Y1029D01*
Y996D01*
Y964D01*
Y932D01*
Y900D01*
Y867D01*
Y835D01*
Y803D01*
Y770D01*
Y738D01*
Y706D01*
Y674D01*
Y641D01*
Y609D01*
Y577D01*
Y545D01*
Y512D01*
Y480D01*
Y448D01*
Y416D01*
Y383D01*
Y351D01*
Y319D01*
Y286D01*
Y254D01*
Y222D01*
Y190D01*
Y157D01*
Y125D01*
Y93D01*
Y61D01*
Y28D01*
Y-4D01*
Y-22D01*
X477576D01*
Y-4D01*
Y28D01*
Y61D01*
Y93D01*
Y125D01*
Y157D01*
Y190D01*
Y222D01*
Y254D01*
Y286D01*
Y319D01*
Y351D01*
Y383D01*
Y416D01*
Y448D01*
Y480D01*
Y512D01*
Y545D01*
Y577D01*
Y609D01*
Y641D01*
Y674D01*
Y706D01*
Y738D01*
Y770D01*
Y803D01*
Y835D01*
Y867D01*
Y900D01*
Y932D01*
Y964D01*
Y996D01*
Y1029D01*
Y1061D01*
Y1093D01*
Y1125D01*
Y1158D01*
Y1190D01*
Y1222D01*
Y1254D01*
Y1287D01*
Y1319D01*
Y1351D01*
Y1383D01*
Y1416D01*
Y1448D01*
Y1480D01*
Y1512D01*
Y1545D01*
Y1577D01*
Y1609D01*
Y1641D01*
Y1674D01*
Y1706D01*
Y1738D01*
Y1770D01*
Y1803D01*
Y1835D01*
Y1867D01*
Y1900D01*
Y1932D01*
Y1964D01*
Y1996D01*
Y2029D01*
Y2061D01*
Y2093D01*
Y2125D01*
Y2158D01*
Y2190D01*
Y2222D01*
Y2254D01*
Y2287D01*
Y2319D01*
Y2351D01*
Y2383D01*
Y2416D01*
Y2448D01*
Y2480D01*
Y2513D01*
Y2545D01*
Y2577D01*
Y2609D01*
Y2642D01*
Y2674D01*
Y2706D01*
Y2738D01*
Y2771D01*
Y2803D01*
Y2835D01*
Y2867D01*
Y2900D01*
Y2932D01*
Y2964D01*
Y2997D01*
Y3029D01*
Y3061D01*
Y3093D01*
Y3125D01*
Y3158D01*
Y3190D01*
Y3222D01*
Y3255D01*
Y3287D01*
Y3319D01*
Y3351D01*
Y3384D01*
Y3416D01*
Y3448D01*
Y3480D01*
Y3513D01*
Y3545D01*
Y3577D01*
Y3609D01*
Y3642D01*
Y3674D01*
Y3706D01*
Y3739D01*
Y3771D01*
Y3803D01*
Y3835D01*
Y3867D01*
Y3900D01*
Y3932D01*
Y3964D01*
Y3997D01*
Y4029D01*
Y4061D01*
Y4093D01*
Y4126D01*
Y4158D01*
Y4190D01*
Y4222D01*
Y4255D01*
Y4287D01*
Y4319D01*
Y4352D01*
Y4384D01*
Y4416D01*
Y4448D01*
Y4481D01*
Y4513D01*
Y4545D01*
Y4577D01*
Y4610D01*
Y4642D01*
Y4674D01*
Y4706D01*
Y4739D01*
Y4771D01*
Y4803D01*
Y4835D01*
Y4868D01*
X477580Y4920D01*
X477590Y4971D01*
X477607Y5021D01*
X477630Y5068D01*
X477659Y5112D01*
X477694Y5151D01*
X477733Y5186D01*
X477777Y5215D01*
X477824Y5238D01*
X477874Y5255D01*
X477925Y5265D01*
X477977Y5269D01*
X478157D01*
Y5287D01*
Y5319D01*
Y5352D01*
Y5384D01*
Y5416D01*
Y5448D01*
Y5481D01*
Y5513D01*
Y5545D01*
Y5577D01*
Y5610D01*
Y5642D01*
Y5674D01*
Y5706D01*
Y5739D01*
Y5771D01*
Y5803D01*
Y5835D01*
Y5868D01*
Y5900D01*
Y5932D01*
Y5965D01*
Y5997D01*
Y6029D01*
Y6061D01*
Y6094D01*
Y6126D01*
Y6158D01*
Y6190D01*
Y6209D01*
D02*
G37*
G36*
X472253D02*
X471281D01*
Y6190D01*
Y6158D01*
Y6126D01*
Y6094D01*
Y6061D01*
Y6029D01*
Y5997D01*
Y5965D01*
Y5932D01*
Y5900D01*
Y5868D01*
Y5835D01*
Y5803D01*
Y5771D01*
Y5739D01*
Y5706D01*
Y5674D01*
Y5642D01*
Y5610D01*
Y5577D01*
Y5545D01*
Y5513D01*
Y5481D01*
Y5448D01*
Y5416D01*
Y5384D01*
Y5352D01*
Y5319D01*
Y5287D01*
Y5255D01*
Y5223D01*
Y5190D01*
Y5158D01*
Y5126D01*
Y5094D01*
Y5061D01*
Y5029D01*
Y4997D01*
Y4964D01*
Y4932D01*
Y4900D01*
Y4868D01*
Y4835D01*
Y4803D01*
Y4771D01*
Y4739D01*
Y4706D01*
Y4674D01*
Y4642D01*
Y4610D01*
Y4577D01*
Y4545D01*
Y4513D01*
Y4481D01*
Y4448D01*
Y4416D01*
Y4384D01*
Y4352D01*
Y4319D01*
Y4287D01*
Y4255D01*
Y4222D01*
Y4190D01*
Y4158D01*
Y4126D01*
Y4093D01*
Y4061D01*
Y4029D01*
Y3997D01*
Y3964D01*
Y3932D01*
Y3900D01*
Y3867D01*
Y3835D01*
Y3803D01*
Y3771D01*
Y3739D01*
Y3706D01*
Y3674D01*
Y3642D01*
Y3609D01*
Y3577D01*
Y3545D01*
Y3513D01*
Y3480D01*
Y3448D01*
Y3416D01*
Y3384D01*
Y3351D01*
Y3319D01*
Y3287D01*
Y3255D01*
Y3222D01*
Y3190D01*
Y3158D01*
Y3125D01*
Y3093D01*
Y3061D01*
Y3029D01*
Y2997D01*
Y2964D01*
Y2932D01*
Y2900D01*
Y2867D01*
Y2835D01*
Y2803D01*
Y2771D01*
Y2738D01*
Y2706D01*
Y2674D01*
Y2642D01*
Y2609D01*
Y2577D01*
Y2545D01*
Y2513D01*
Y2480D01*
Y2448D01*
Y2416D01*
Y2383D01*
Y2351D01*
Y2319D01*
Y2287D01*
Y2254D01*
Y2222D01*
Y2190D01*
Y2158D01*
Y2125D01*
Y2093D01*
Y2061D01*
Y2029D01*
Y1996D01*
Y1964D01*
Y1932D01*
Y1900D01*
Y1867D01*
Y1835D01*
Y1803D01*
Y1770D01*
Y1738D01*
Y1706D01*
Y1674D01*
Y1641D01*
Y1609D01*
Y1577D01*
Y1545D01*
Y1512D01*
Y1480D01*
Y1448D01*
Y1416D01*
Y1383D01*
Y1351D01*
Y1319D01*
Y1287D01*
Y1254D01*
Y1222D01*
Y1190D01*
Y1158D01*
Y1125D01*
Y1093D01*
Y1061D01*
Y1029D01*
Y996D01*
Y964D01*
Y932D01*
Y900D01*
Y867D01*
Y835D01*
Y803D01*
Y770D01*
Y738D01*
Y706D01*
Y674D01*
Y641D01*
Y609D01*
Y577D01*
Y545D01*
Y512D01*
Y480D01*
Y448D01*
Y416D01*
Y383D01*
Y351D01*
Y319D01*
Y286D01*
Y254D01*
Y222D01*
Y190D01*
Y157D01*
Y125D01*
Y93D01*
Y61D01*
Y28D01*
Y-4D01*
Y-22D01*
X472253D01*
Y-4D01*
Y28D01*
Y61D01*
Y93D01*
Y125D01*
Y157D01*
Y190D01*
Y222D01*
Y254D01*
Y286D01*
Y319D01*
Y351D01*
Y383D01*
Y416D01*
Y448D01*
Y480D01*
Y512D01*
Y545D01*
Y577D01*
Y609D01*
Y641D01*
Y674D01*
Y706D01*
Y738D01*
Y770D01*
Y803D01*
Y835D01*
Y867D01*
Y900D01*
Y932D01*
Y964D01*
Y996D01*
Y1029D01*
Y1061D01*
Y1093D01*
Y1125D01*
Y1158D01*
Y1190D01*
Y1222D01*
Y1254D01*
Y1287D01*
Y1319D01*
Y1351D01*
Y1383D01*
Y1416D01*
Y1448D01*
Y1480D01*
Y1512D01*
Y1545D01*
Y1577D01*
Y1609D01*
Y1641D01*
Y1674D01*
Y1706D01*
Y1738D01*
Y1770D01*
Y1803D01*
Y1835D01*
Y1867D01*
Y1900D01*
Y1932D01*
Y1964D01*
Y1996D01*
Y2029D01*
Y2061D01*
Y2093D01*
Y2125D01*
Y2158D01*
Y2190D01*
Y2222D01*
Y2254D01*
Y2287D01*
Y2319D01*
Y2351D01*
Y2383D01*
Y2416D01*
Y2448D01*
Y2480D01*
Y2513D01*
Y2545D01*
Y2577D01*
Y2609D01*
Y2642D01*
Y2674D01*
Y2706D01*
Y2738D01*
Y2771D01*
Y2803D01*
Y2835D01*
Y2867D01*
Y2900D01*
Y2932D01*
Y2964D01*
Y2997D01*
Y3029D01*
Y3061D01*
Y3093D01*
Y3125D01*
Y3158D01*
Y3190D01*
Y3222D01*
Y3255D01*
Y3287D01*
Y3319D01*
Y3351D01*
Y3384D01*
Y3416D01*
Y3448D01*
Y3480D01*
Y3513D01*
Y3545D01*
Y3577D01*
Y3609D01*
Y3642D01*
Y3674D01*
Y3706D01*
Y3739D01*
Y3771D01*
Y3803D01*
Y3835D01*
Y3867D01*
Y3900D01*
Y3932D01*
Y3964D01*
Y3997D01*
Y4029D01*
Y4061D01*
Y4093D01*
Y4126D01*
Y4158D01*
Y4190D01*
Y4222D01*
Y4255D01*
Y4287D01*
Y4319D01*
Y4352D01*
Y4384D01*
Y4416D01*
Y4448D01*
Y4481D01*
Y4513D01*
Y4545D01*
Y4577D01*
Y4610D01*
Y4642D01*
Y4674D01*
Y4706D01*
Y4739D01*
Y4771D01*
Y4803D01*
Y4835D01*
Y4868D01*
Y4900D01*
Y4932D01*
Y4964D01*
Y4997D01*
Y5029D01*
Y5061D01*
Y5094D01*
Y5126D01*
Y5158D01*
Y5190D01*
Y5223D01*
Y5255D01*
Y5287D01*
Y5319D01*
Y5352D01*
Y5384D01*
Y5416D01*
Y5448D01*
Y5481D01*
Y5513D01*
Y5545D01*
Y5577D01*
Y5610D01*
Y5642D01*
Y5674D01*
Y5706D01*
Y5739D01*
Y5771D01*
Y5803D01*
Y5835D01*
Y5868D01*
Y5900D01*
Y5932D01*
Y5965D01*
Y5997D01*
Y6029D01*
Y6061D01*
Y6094D01*
Y6126D01*
Y6158D01*
Y6190D01*
Y6209D01*
D02*
G37*
G36*
X470078D02*
X465506D01*
Y6190D01*
Y6158D01*
Y6126D01*
Y6094D01*
Y6061D01*
Y6029D01*
Y5997D01*
Y5965D01*
Y5932D01*
Y5900D01*
Y5868D01*
Y5835D01*
Y5803D01*
Y5771D01*
Y5739D01*
Y5706D01*
Y5674D01*
Y5642D01*
Y5610D01*
Y5577D01*
Y5545D01*
Y5513D01*
Y5481D01*
Y5448D01*
Y5416D01*
Y5384D01*
Y5352D01*
Y5319D01*
Y5287D01*
Y5269D01*
X466815D01*
X466867Y5265D01*
X466919Y5255D01*
X466968Y5238D01*
X467015Y5215D01*
X467059Y5186D01*
X467098Y5151D01*
X467113Y5134D01*
X467131Y5119D01*
X467146Y5102D01*
X467163Y5087D01*
X467197Y5047D01*
X467227Y5004D01*
X467250Y4956D01*
X467252Y4949D01*
X467259Y4939D01*
X467282Y4892D01*
X467299Y4842D01*
X467309Y4791D01*
X467312Y4739D01*
Y4706D01*
Y4674D01*
Y4642D01*
Y4610D01*
Y4577D01*
Y4545D01*
Y4513D01*
Y4481D01*
Y4448D01*
Y4416D01*
Y4384D01*
Y4352D01*
Y4319D01*
Y4287D01*
Y4255D01*
Y4222D01*
Y4190D01*
Y4158D01*
Y4126D01*
Y4093D01*
Y4061D01*
Y4029D01*
Y3997D01*
Y3964D01*
Y3932D01*
Y3900D01*
Y3867D01*
Y3835D01*
Y3803D01*
Y3771D01*
Y3739D01*
Y3706D01*
Y3674D01*
Y3642D01*
Y3609D01*
Y3577D01*
Y3545D01*
Y3513D01*
Y3480D01*
Y3448D01*
Y3416D01*
Y3384D01*
Y3351D01*
Y3319D01*
Y3287D01*
Y3255D01*
Y3222D01*
Y3190D01*
Y3158D01*
Y3125D01*
Y3093D01*
Y3061D01*
Y3029D01*
Y2997D01*
Y2964D01*
Y2932D01*
Y2900D01*
Y2867D01*
Y2835D01*
Y2803D01*
Y2771D01*
Y2738D01*
Y2706D01*
Y2674D01*
Y2642D01*
Y2609D01*
Y2577D01*
Y2545D01*
Y2513D01*
Y2480D01*
Y2448D01*
Y2416D01*
Y2383D01*
Y2351D01*
Y2319D01*
Y2287D01*
Y2254D01*
Y2222D01*
Y2190D01*
Y2158D01*
Y2125D01*
Y2093D01*
Y2061D01*
Y2029D01*
Y1996D01*
Y1964D01*
Y1932D01*
Y1900D01*
Y1867D01*
Y1835D01*
Y1803D01*
Y1770D01*
Y1738D01*
Y1706D01*
Y1674D01*
Y1641D01*
Y1609D01*
Y1577D01*
Y1545D01*
Y1512D01*
Y1480D01*
Y1448D01*
Y1416D01*
Y1383D01*
Y1351D01*
Y1319D01*
Y1287D01*
Y1254D01*
Y1222D01*
Y1190D01*
Y1158D01*
Y1125D01*
Y1093D01*
Y1061D01*
Y1029D01*
Y996D01*
Y964D01*
Y932D01*
Y900D01*
Y867D01*
Y835D01*
Y803D01*
Y770D01*
Y738D01*
Y706D01*
Y674D01*
Y641D01*
Y609D01*
Y577D01*
Y545D01*
Y512D01*
Y480D01*
Y448D01*
Y416D01*
Y383D01*
Y351D01*
Y319D01*
Y286D01*
Y254D01*
Y222D01*
Y190D01*
Y157D01*
Y125D01*
Y93D01*
Y61D01*
Y28D01*
Y-4D01*
Y-22D01*
X468285D01*
Y-4D01*
Y28D01*
Y61D01*
Y93D01*
Y125D01*
Y157D01*
Y190D01*
Y222D01*
Y254D01*
Y286D01*
Y319D01*
Y351D01*
Y383D01*
Y416D01*
Y448D01*
Y480D01*
Y512D01*
Y545D01*
Y577D01*
Y609D01*
Y641D01*
Y674D01*
Y706D01*
Y738D01*
Y770D01*
Y803D01*
Y835D01*
Y867D01*
Y900D01*
Y932D01*
Y964D01*
Y996D01*
Y1029D01*
Y1061D01*
Y1093D01*
Y1125D01*
Y1158D01*
Y1190D01*
Y1222D01*
Y1254D01*
Y1287D01*
Y1319D01*
Y1351D01*
Y1383D01*
Y1416D01*
Y1448D01*
Y1480D01*
Y1512D01*
Y1545D01*
Y1577D01*
Y1609D01*
Y1641D01*
Y1674D01*
Y1706D01*
Y1738D01*
Y1770D01*
Y1803D01*
Y1835D01*
Y1867D01*
Y1900D01*
Y1932D01*
Y1964D01*
Y1996D01*
Y2029D01*
Y2061D01*
Y2093D01*
Y2125D01*
Y2158D01*
Y2190D01*
Y2222D01*
Y2254D01*
Y2287D01*
Y2319D01*
Y2351D01*
Y2383D01*
Y2416D01*
Y2448D01*
Y2480D01*
Y2513D01*
Y2545D01*
Y2577D01*
Y2609D01*
Y2642D01*
Y2674D01*
Y2706D01*
Y2738D01*
Y2771D01*
Y2803D01*
Y2835D01*
Y2867D01*
Y2900D01*
Y2932D01*
Y2964D01*
Y2997D01*
Y3029D01*
Y3061D01*
Y3093D01*
Y3125D01*
Y3158D01*
Y3190D01*
Y3222D01*
Y3255D01*
Y3287D01*
Y3319D01*
Y3351D01*
Y3384D01*
Y3416D01*
Y3448D01*
Y3480D01*
Y3513D01*
Y3545D01*
Y3577D01*
Y3609D01*
Y3642D01*
Y3674D01*
Y3706D01*
Y3739D01*
Y3771D01*
Y3803D01*
Y3835D01*
Y3867D01*
Y3900D01*
Y3932D01*
Y3964D01*
Y3997D01*
Y4029D01*
Y4061D01*
Y4093D01*
Y4126D01*
Y4158D01*
Y4190D01*
Y4222D01*
Y4255D01*
Y4287D01*
Y4319D01*
Y4352D01*
Y4384D01*
Y4416D01*
Y4448D01*
Y4481D01*
Y4513D01*
Y4545D01*
Y4577D01*
Y4610D01*
Y4642D01*
Y4674D01*
Y4706D01*
Y4739D01*
Y4771D01*
Y4803D01*
X468289Y4855D01*
X468299Y4907D01*
X468316Y4956D01*
X468339Y5004D01*
X468368Y5047D01*
X468402Y5087D01*
X468420Y5102D01*
X468435Y5119D01*
X468452Y5134D01*
X468467Y5151D01*
X468506Y5186D01*
X468550Y5215D01*
X468597Y5238D01*
X468647Y5255D01*
X468698Y5265D01*
X468750Y5269D01*
X470092D01*
Y5287D01*
Y5319D01*
Y5352D01*
Y5384D01*
Y5416D01*
Y5448D01*
Y5481D01*
Y5513D01*
Y5545D01*
Y5577D01*
Y5610D01*
Y5642D01*
Y5674D01*
Y5706D01*
Y5739D01*
Y5771D01*
Y5803D01*
Y5835D01*
Y5868D01*
Y5900D01*
Y5932D01*
Y5965D01*
Y5997D01*
Y6029D01*
Y6061D01*
Y6094D01*
Y6126D01*
Y6158D01*
Y6190D01*
Y6204D01*
X470081Y6207D01*
X470078Y6209D01*
D02*
G37*
G36*
X462994Y-1052D02*
X462971Y-1087D01*
X462950Y-1111D01*
X462936Y-1140D01*
X462907Y-1183D01*
X462872Y-1223D01*
X462855Y-1238D01*
X462840Y-1255D01*
X462823Y-1270D01*
X462807Y-1287D01*
X462790Y-1303D01*
X462775Y-1320D01*
X462758Y-1335D01*
X462743Y-1352D01*
X462726Y-1367D01*
X462711Y-1384D01*
X462693Y-1399D01*
X462678Y-1417D01*
X462661Y-1431D01*
X462646Y-1449D01*
X462629Y-1464D01*
X462614Y-1481D01*
X462574Y-1516D01*
X462531Y-1545D01*
X462501Y-1559D01*
X462488Y-1571D01*
X462994D01*
Y-1552D01*
Y-1520D01*
Y-1488D01*
Y-1456D01*
Y-1423D01*
Y-1391D01*
Y-1359D01*
Y-1327D01*
Y-1294D01*
Y-1262D01*
Y-1230D01*
Y-1198D01*
Y-1165D01*
Y-1133D01*
Y-1101D01*
Y-1068D01*
Y-1052D01*
D02*
G37*
G36*
Y-3179D02*
X462443D01*
X462444Y-3180D01*
X462452Y-3182D01*
X462499Y-3206D01*
X462542Y-3235D01*
X462582Y-3269D01*
X462597Y-3286D01*
X462598Y-3288D01*
X462628Y-3302D01*
X462671Y-3331D01*
X462711Y-3366D01*
X462726Y-3383D01*
X462726Y-3383D01*
X462743Y-3398D01*
X462758Y-3415D01*
X462775Y-3430D01*
X462790Y-3448D01*
X462807Y-3463D01*
X462842Y-3502D01*
X462871Y-3546D01*
X462886Y-3575D01*
X462887Y-3577D01*
X462904Y-3592D01*
X462939Y-3631D01*
X462968Y-3675D01*
X462991Y-3722D01*
X462994Y-3730D01*
X462994Y-3730D01*
Y-3714D01*
Y-3682D01*
Y-3650D01*
Y-3617D01*
Y-3585D01*
Y-3553D01*
Y-3520D01*
Y-3488D01*
Y-3456D01*
Y-3424D01*
Y-3391D01*
Y-3359D01*
Y-3327D01*
Y-3295D01*
Y-3262D01*
Y-3230D01*
Y-3198D01*
Y-3179D01*
D02*
G37*
G36*
X481756Y-1405D02*
X481659D01*
X481648Y-1417D01*
X481631Y-1431D01*
X481616Y-1449D01*
X481599Y-1464D01*
X481584Y-1481D01*
X481567Y-1496D01*
X481552Y-1513D01*
X481534Y-1528D01*
X481519Y-1546D01*
X481502Y-1561D01*
X481487Y-1578D01*
X481470Y-1593D01*
X481455Y-1610D01*
X481438Y-1625D01*
X481423Y-1642D01*
X481405Y-1657D01*
X481390Y-1675D01*
X481373Y-1690D01*
X481358Y-1707D01*
X481341Y-1722D01*
X481326Y-1739D01*
X481309Y-1754D01*
X481293Y-1771D01*
X481276Y-1787D01*
X481261Y-1804D01*
X481244Y-1819D01*
X481229Y-1836D01*
X481212Y-1851D01*
X481197Y-1868D01*
X481179Y-1883D01*
X481164Y-1900D01*
X481147Y-1915D01*
X481132Y-1933D01*
X481115Y-1948D01*
X481100Y-1965D01*
X481083Y-1980D01*
X481068Y-1997D01*
X481050Y-2012D01*
X481035Y-2029D01*
X481018Y-2045D01*
X481003Y-2062D01*
X480986Y-2077D01*
X480976Y-2088D01*
X480971Y-2094D01*
X480954Y-2109D01*
X480939Y-2126D01*
X480921Y-2141D01*
X480906Y-2159D01*
X480889Y-2174D01*
X480880Y-2184D01*
X481365D01*
X481417Y-2187D01*
X481469Y-2198D01*
X481518Y-2214D01*
X481565Y-2238D01*
X481609Y-2267D01*
X481648Y-2301D01*
X481683Y-2341D01*
X481712Y-2384D01*
X481735Y-2431D01*
X481752Y-2481D01*
X481762Y-2533D01*
X481766Y-2585D01*
Y-2617D01*
Y-2649D01*
Y-2682D01*
Y-2714D01*
Y-2746D01*
Y-2778D01*
Y-2811D01*
Y-2843D01*
Y-2875D01*
Y-2907D01*
Y-2940D01*
Y-2972D01*
Y-3004D01*
Y-3036D01*
Y-3069D01*
Y-3101D01*
Y-3133D01*
Y-3165D01*
Y-3198D01*
Y-3230D01*
Y-3262D01*
Y-3295D01*
Y-3327D01*
Y-3359D01*
Y-3391D01*
Y-3424D01*
Y-3456D01*
Y-3488D01*
Y-3520D01*
Y-3553D01*
Y-3585D01*
Y-3617D01*
Y-3650D01*
Y-3682D01*
Y-3714D01*
Y-3746D01*
Y-3779D01*
Y-3811D01*
Y-3843D01*
Y-3875D01*
Y-3907D01*
Y-3940D01*
Y-3972D01*
Y-4004D01*
Y-4037D01*
Y-4069D01*
Y-4101D01*
Y-4133D01*
Y-4166D01*
Y-4198D01*
Y-4230D01*
Y-4262D01*
Y-4295D01*
Y-4327D01*
Y-4359D01*
X481762Y-4411D01*
X481752Y-4463D01*
X481735Y-4513D01*
X481712Y-4560D01*
X481683Y-4603D01*
X481648Y-4643D01*
X481609Y-4677D01*
X481565Y-4706D01*
X481518Y-4730D01*
X481469Y-4746D01*
X481417Y-4757D01*
X481365Y-4760D01*
X479010D01*
X478957Y-4757D01*
X478906Y-4746D01*
X478856Y-4730D01*
X478809Y-4706D01*
X478766Y-4677D01*
X478726Y-4643D01*
X478692Y-4603D01*
X478663Y-4561D01*
X478663Y-4561D01*
X478648Y-4578D01*
X478631Y-4593D01*
X478617Y-4609D01*
X478616Y-4610D01*
X478599Y-4625D01*
X478583Y-4643D01*
X478566Y-4658D01*
X478551Y-4675D01*
X478534Y-4690D01*
X478519Y-4707D01*
X478502Y-4722D01*
X478487Y-4739D01*
X478470Y-4755D01*
X478454Y-4772D01*
X478437Y-4787D01*
X478423Y-4803D01*
X478422Y-4804D01*
X478405Y-4819D01*
X478390Y-4836D01*
X478373Y-4851D01*
X478358Y-4868D01*
X478340Y-4884D01*
X478325Y-4901D01*
X478308Y-4916D01*
X478293Y-4933D01*
X478276Y-4948D01*
X478261Y-4965D01*
X478244Y-4980D01*
X478229Y-4998D01*
X478211Y-5013D01*
X478196Y-5030D01*
X478179Y-5045D01*
X478164Y-5062D01*
X478147Y-5077D01*
X478132Y-5094D01*
X478116Y-5108D01*
X478115Y-5109D01*
X478099Y-5127D01*
X478082Y-5142D01*
X478067Y-5159D01*
X478050Y-5174D01*
X478035Y-5191D01*
X478018Y-5206D01*
X478003Y-5223D01*
X477985Y-5238D01*
X477971Y-5256D01*
X477953Y-5271D01*
X477938Y-5288D01*
X477921Y-5303D01*
X477906Y-5320D01*
X477889Y-5335D01*
X477874Y-5352D01*
X477856Y-5367D01*
X477841Y-5385D01*
X477824Y-5400D01*
X477809Y-5417D01*
X477792Y-5432D01*
X477777Y-5449D01*
X477738Y-5484D01*
X477694Y-5513D01*
X477665Y-5527D01*
X477663Y-5529D01*
X477655Y-5537D01*
X477648Y-5546D01*
X477636Y-5556D01*
Y-5585D01*
Y-5617D01*
Y-5650D01*
Y-5682D01*
Y-5714D01*
Y-5746D01*
Y-5779D01*
Y-5811D01*
Y-5843D01*
Y-5875D01*
Y-5908D01*
Y-5940D01*
Y-5972D01*
Y-6005D01*
Y-6037D01*
Y-6069D01*
Y-6101D01*
Y-6134D01*
Y-6166D01*
Y-6198D01*
Y-6230D01*
Y-6263D01*
Y-6295D01*
Y-6327D01*
Y-6359D01*
Y-6392D01*
Y-6424D01*
Y-6456D01*
Y-6488D01*
Y-6521D01*
Y-6553D01*
Y-6585D01*
Y-6617D01*
Y-6650D01*
Y-6682D01*
Y-6714D01*
Y-6747D01*
Y-6779D01*
Y-6811D01*
Y-6843D01*
Y-6876D01*
Y-6908D01*
Y-6940D01*
Y-6972D01*
Y-7005D01*
Y-7037D01*
Y-7069D01*
Y-7102D01*
Y-7134D01*
Y-7166D01*
Y-7198D01*
Y-7231D01*
Y-7263D01*
Y-7295D01*
Y-7327D01*
Y-7360D01*
Y-7392D01*
Y-7424D01*
Y-7456D01*
Y-7489D01*
Y-7521D01*
Y-7553D01*
Y-7585D01*
Y-7618D01*
Y-7636D01*
X478609D01*
Y-7618D01*
Y-7585D01*
Y-7553D01*
Y-7521D01*
Y-7489D01*
Y-7456D01*
Y-7424D01*
Y-7392D01*
Y-7360D01*
Y-7327D01*
Y-7295D01*
Y-7263D01*
Y-7231D01*
Y-7198D01*
Y-7166D01*
Y-7134D01*
Y-7102D01*
Y-7069D01*
Y-7037D01*
Y-7005D01*
Y-6972D01*
Y-6940D01*
Y-6908D01*
Y-6876D01*
Y-6843D01*
Y-6811D01*
Y-6779D01*
Y-6747D01*
Y-6714D01*
Y-6682D01*
Y-6650D01*
Y-6617D01*
Y-6585D01*
Y-6553D01*
Y-6521D01*
Y-6488D01*
Y-6456D01*
Y-6424D01*
Y-6392D01*
Y-6359D01*
Y-6327D01*
Y-6295D01*
Y-6263D01*
Y-6230D01*
Y-6198D01*
Y-6166D01*
Y-6134D01*
Y-6101D01*
Y-6069D01*
Y-6037D01*
Y-6005D01*
Y-5972D01*
X478612Y-5920D01*
X478623Y-5869D01*
X478639Y-5819D01*
X478663Y-5772D01*
X478669Y-5762D01*
X478672Y-5754D01*
X478695Y-5707D01*
X478724Y-5664D01*
X478759Y-5624D01*
X478798Y-5590D01*
X478842Y-5561D01*
X478889Y-5537D01*
X478897Y-5535D01*
X478906Y-5528D01*
X478953Y-5505D01*
X479003Y-5488D01*
X479054Y-5478D01*
X479107Y-5475D01*
X481268D01*
X481320Y-5478D01*
X481372Y-5488D01*
X481422Y-5505D01*
X481468Y-5528D01*
X481478Y-5535D01*
X481486Y-5537D01*
X481533Y-5561D01*
X481577Y-5590D01*
X481616Y-5624D01*
X481651Y-5664D01*
X481680Y-5707D01*
X481703Y-5754D01*
X481706Y-5762D01*
X481712Y-5772D01*
X481735Y-5819D01*
X481752Y-5869D01*
X481762Y-5920D01*
X481766Y-5972D01*
Y-6005D01*
Y-6037D01*
Y-6069D01*
Y-6101D01*
Y-6134D01*
Y-6166D01*
Y-6198D01*
Y-6230D01*
Y-6263D01*
Y-6295D01*
Y-6327D01*
Y-6359D01*
Y-6392D01*
Y-6424D01*
Y-6456D01*
Y-6488D01*
Y-6521D01*
Y-6553D01*
Y-6585D01*
Y-6617D01*
Y-6650D01*
Y-6682D01*
Y-6714D01*
Y-6747D01*
Y-6779D01*
Y-6811D01*
Y-6843D01*
Y-6876D01*
Y-6908D01*
Y-6940D01*
Y-6972D01*
Y-7005D01*
Y-7037D01*
Y-7069D01*
Y-7102D01*
Y-7134D01*
Y-7166D01*
Y-7198D01*
Y-7231D01*
Y-7263D01*
Y-7295D01*
Y-7327D01*
Y-7360D01*
Y-7392D01*
Y-7424D01*
Y-7456D01*
Y-7489D01*
Y-7521D01*
Y-7553D01*
Y-7585D01*
Y-7618D01*
Y-7636D01*
X482738D01*
Y-7618D01*
Y-7585D01*
Y-7553D01*
Y-7521D01*
Y-7489D01*
Y-7456D01*
Y-7424D01*
Y-7392D01*
Y-7360D01*
Y-7327D01*
Y-7295D01*
Y-7263D01*
Y-7231D01*
Y-7198D01*
Y-7166D01*
Y-7134D01*
Y-7102D01*
Y-7069D01*
Y-7037D01*
Y-7005D01*
Y-6972D01*
Y-6940D01*
Y-6908D01*
Y-6876D01*
Y-6843D01*
Y-6811D01*
Y-6779D01*
Y-6747D01*
Y-6714D01*
Y-6682D01*
Y-6650D01*
Y-6617D01*
Y-6585D01*
Y-6553D01*
Y-6521D01*
Y-6488D01*
Y-6456D01*
Y-6424D01*
Y-6392D01*
Y-6359D01*
Y-6327D01*
Y-6295D01*
Y-6263D01*
Y-6230D01*
Y-6198D01*
Y-6166D01*
Y-6134D01*
Y-6101D01*
Y-6069D01*
Y-6037D01*
Y-6005D01*
Y-5972D01*
Y-5940D01*
Y-5908D01*
Y-5875D01*
Y-5843D01*
Y-5811D01*
Y-5779D01*
Y-5746D01*
Y-5714D01*
Y-5682D01*
Y-5650D01*
Y-5617D01*
Y-5585D01*
Y-5553D01*
Y-5521D01*
Y-5488D01*
Y-5456D01*
Y-5424D01*
Y-5392D01*
Y-5359D01*
Y-5327D01*
Y-5295D01*
Y-5263D01*
Y-5230D01*
Y-5198D01*
Y-5166D01*
Y-5133D01*
Y-5101D01*
Y-5069D01*
Y-5037D01*
Y-5004D01*
Y-4972D01*
Y-4940D01*
Y-4908D01*
Y-4875D01*
Y-4843D01*
Y-4811D01*
Y-4779D01*
Y-4746D01*
Y-4714D01*
Y-4682D01*
Y-4650D01*
Y-4617D01*
Y-4585D01*
Y-4553D01*
Y-4521D01*
Y-4488D01*
Y-4456D01*
Y-4424D01*
Y-4391D01*
Y-4359D01*
Y-4327D01*
Y-4295D01*
Y-4262D01*
Y-4230D01*
Y-4198D01*
Y-4166D01*
Y-4133D01*
Y-4101D01*
Y-4069D01*
Y-4037D01*
Y-4004D01*
Y-3972D01*
Y-3940D01*
Y-3907D01*
Y-3875D01*
Y-3843D01*
Y-3811D01*
Y-3779D01*
Y-3746D01*
Y-3714D01*
Y-3682D01*
Y-3650D01*
Y-3617D01*
Y-3585D01*
Y-3553D01*
Y-3520D01*
Y-3488D01*
Y-3456D01*
Y-3424D01*
Y-3391D01*
Y-3359D01*
Y-3327D01*
Y-3295D01*
Y-3262D01*
Y-3230D01*
Y-3198D01*
Y-3165D01*
Y-3133D01*
Y-3101D01*
Y-3069D01*
Y-3036D01*
Y-3004D01*
Y-2972D01*
Y-2940D01*
Y-2907D01*
Y-2875D01*
Y-2843D01*
Y-2811D01*
Y-2778D01*
Y-2746D01*
Y-2714D01*
Y-2682D01*
Y-2649D01*
Y-2617D01*
Y-2585D01*
Y-2553D01*
Y-2520D01*
Y-2488D01*
Y-2456D01*
Y-2424D01*
Y-2391D01*
Y-2387D01*
X482737Y-2383D01*
X482720Y-2334D01*
X482710Y-2282D01*
X482709Y-2269D01*
X482708Y-2262D01*
X482704Y-2254D01*
X482693Y-2222D01*
X482680Y-2206D01*
X482662Y-2191D01*
X482647Y-2174D01*
X482630Y-2159D01*
X482629Y-2157D01*
X482615Y-2141D01*
X482598Y-2126D01*
X482583Y-2109D01*
X482565Y-2094D01*
X482550Y-2077D01*
X482533Y-2062D01*
X482518Y-2045D01*
X482501Y-2029D01*
X482495Y-2022D01*
X482486Y-2012D01*
X482469Y-1997D01*
X482454Y-1980D01*
X482436Y-1965D01*
X482421Y-1948D01*
X482404Y-1933D01*
X482403Y-1931D01*
X482389Y-1915D01*
X482372Y-1900D01*
X482357Y-1883D01*
X482340Y-1868D01*
X482325Y-1851D01*
X482307Y-1836D01*
X482292Y-1819D01*
X482275Y-1804D01*
X482260Y-1787D01*
X482243Y-1771D01*
X482228Y-1754D01*
X482211Y-1739D01*
X482196Y-1722D01*
X482178Y-1707D01*
X482163Y-1690D01*
X482146Y-1675D01*
X482131Y-1657D01*
X482114Y-1642D01*
X482113Y-1641D01*
X482099Y-1625D01*
X482082Y-1610D01*
X482080Y-1609D01*
X482066Y-1593D01*
X482049Y-1578D01*
X482034Y-1561D01*
X482017Y-1546D01*
X482002Y-1528D01*
X481985Y-1513D01*
X481970Y-1496D01*
X481952Y-1481D01*
X481937Y-1464D01*
X481936Y-1462D01*
X481907Y-1448D01*
X481897Y-1442D01*
X481889Y-1439D01*
X481881Y-1435D01*
X481861Y-1434D01*
X481810Y-1424D01*
X481760Y-1407D01*
X481756Y-1405D01*
D02*
G37*
G36*
X479530Y10048D02*
X479507D01*
Y10029D01*
Y9997D01*
Y9965D01*
Y9933D01*
Y9900D01*
Y9868D01*
Y9836D01*
Y9804D01*
Y9771D01*
Y9739D01*
Y9707D01*
Y9675D01*
Y9642D01*
Y9610D01*
Y9578D01*
Y9546D01*
Y9513D01*
Y9481D01*
Y9449D01*
Y9417D01*
Y9384D01*
Y9352D01*
Y9320D01*
Y9287D01*
Y9255D01*
Y9223D01*
Y9191D01*
Y9159D01*
Y9126D01*
Y9094D01*
Y9062D01*
Y9029D01*
Y8997D01*
Y8965D01*
Y8933D01*
Y8900D01*
Y8868D01*
Y8836D01*
Y8804D01*
Y8771D01*
Y8739D01*
Y8707D01*
Y8675D01*
Y8642D01*
Y8610D01*
Y8578D01*
Y8546D01*
Y8513D01*
Y8481D01*
Y8449D01*
Y8416D01*
Y8384D01*
Y8352D01*
Y8320D01*
Y8287D01*
Y8255D01*
Y8223D01*
Y8191D01*
Y8158D01*
Y8126D01*
Y8094D01*
Y8062D01*
Y8029D01*
Y7997D01*
Y7965D01*
Y7932D01*
Y7900D01*
Y7868D01*
Y7836D01*
Y7803D01*
Y7771D01*
Y7739D01*
Y7707D01*
Y7674D01*
Y7642D01*
Y7610D01*
Y7578D01*
Y7545D01*
Y7513D01*
Y7481D01*
Y7449D01*
Y7416D01*
Y7384D01*
Y7352D01*
Y7320D01*
Y7287D01*
Y7255D01*
Y7223D01*
Y7191D01*
Y7158D01*
Y7126D01*
Y7094D01*
Y7062D01*
Y7029D01*
Y6997D01*
Y6965D01*
Y6932D01*
Y6900D01*
Y6868D01*
Y6836D01*
Y6803D01*
Y6771D01*
Y6739D01*
Y6707D01*
Y6674D01*
Y6642D01*
Y6610D01*
Y6577D01*
Y6545D01*
Y6513D01*
Y6481D01*
Y6448D01*
Y6416D01*
Y6384D01*
Y6352D01*
Y6319D01*
Y6287D01*
Y6255D01*
Y6223D01*
Y6190D01*
Y6158D01*
Y6126D01*
Y6094D01*
Y6061D01*
Y6029D01*
Y5997D01*
Y5965D01*
Y5932D01*
Y5900D01*
Y5868D01*
Y5835D01*
Y5803D01*
Y5771D01*
Y5739D01*
Y5706D01*
Y5674D01*
Y5642D01*
Y5610D01*
Y5577D01*
Y5545D01*
Y5513D01*
Y5481D01*
Y5448D01*
Y5416D01*
Y5384D01*
Y5352D01*
Y5319D01*
Y5287D01*
Y5255D01*
Y5223D01*
Y5190D01*
Y5158D01*
Y5126D01*
Y5094D01*
Y5061D01*
Y5029D01*
Y4997D01*
Y4964D01*
Y4932D01*
Y4900D01*
Y4868D01*
Y4835D01*
Y4803D01*
Y4771D01*
Y4739D01*
Y4706D01*
Y4674D01*
Y4642D01*
Y4610D01*
Y4577D01*
Y4545D01*
Y4513D01*
Y4481D01*
Y4448D01*
Y4416D01*
Y4384D01*
Y4352D01*
Y4319D01*
Y4287D01*
Y4255D01*
Y4222D01*
Y4190D01*
Y4158D01*
Y4126D01*
Y4093D01*
Y4061D01*
Y4029D01*
Y3997D01*
Y3964D01*
Y3932D01*
Y3900D01*
Y3867D01*
Y3835D01*
Y3803D01*
Y3771D01*
Y3739D01*
Y3706D01*
Y3674D01*
Y3642D01*
Y3609D01*
Y3577D01*
Y3545D01*
Y3513D01*
Y3480D01*
Y3448D01*
Y3416D01*
Y3384D01*
Y3351D01*
Y3319D01*
Y3287D01*
Y3255D01*
Y3222D01*
Y3190D01*
Y3158D01*
Y3125D01*
Y3093D01*
Y3061D01*
Y3029D01*
Y2997D01*
Y2964D01*
Y2932D01*
Y2900D01*
Y2867D01*
Y2835D01*
Y2803D01*
Y2771D01*
Y2738D01*
Y2706D01*
Y2674D01*
Y2642D01*
Y2609D01*
Y2577D01*
Y2545D01*
Y2513D01*
Y2480D01*
Y2448D01*
Y2416D01*
Y2383D01*
Y2351D01*
Y2319D01*
Y2287D01*
Y2254D01*
Y2222D01*
Y2190D01*
Y2158D01*
Y2125D01*
Y2093D01*
Y2061D01*
Y2029D01*
Y1996D01*
Y1964D01*
Y1932D01*
Y1900D01*
Y1867D01*
Y1835D01*
Y1803D01*
Y1770D01*
Y1738D01*
Y1706D01*
Y1674D01*
Y1641D01*
Y1609D01*
Y1577D01*
Y1545D01*
Y1512D01*
Y1480D01*
Y1448D01*
Y1416D01*
Y1383D01*
Y1351D01*
Y1319D01*
Y1287D01*
Y1254D01*
Y1222D01*
Y1190D01*
Y1158D01*
Y1125D01*
Y1093D01*
Y1061D01*
Y1029D01*
Y996D01*
Y964D01*
Y932D01*
Y900D01*
Y867D01*
Y835D01*
Y803D01*
Y770D01*
Y738D01*
Y706D01*
Y674D01*
Y641D01*
Y609D01*
Y577D01*
Y545D01*
Y512D01*
Y480D01*
Y448D01*
Y416D01*
Y383D01*
Y351D01*
Y319D01*
Y286D01*
Y254D01*
Y222D01*
Y190D01*
Y157D01*
Y125D01*
Y93D01*
Y61D01*
Y28D01*
Y-4D01*
Y-36D01*
Y-68D01*
Y-101D01*
Y-133D01*
Y-165D01*
Y-197D01*
Y-230D01*
X479504Y-282D01*
X479494Y-334D01*
X479477Y-383D01*
X479454Y-430D01*
X479425Y-474D01*
X479390Y-513D01*
X479373Y-528D01*
X479358Y-545D01*
X479341Y-561D01*
X479325Y-578D01*
X479308Y-593D01*
X479293Y-610D01*
X479276Y-625D01*
X479261Y-642D01*
X479244Y-657D01*
X479230Y-673D01*
X479229Y-674D01*
X479212Y-690D01*
X479196Y-707D01*
X479179Y-722D01*
X479164Y-739D01*
X479147Y-754D01*
X479142Y-760D01*
X479132Y-771D01*
X479115Y-786D01*
X479100Y-804D01*
X479082Y-819D01*
X479067Y-836D01*
X479052Y-850D01*
X479050Y-851D01*
X479035Y-868D01*
X479018Y-883D01*
X479003Y-900D01*
X478986Y-915D01*
X478971Y-933D01*
X478953Y-948D01*
X478938Y-965D01*
X478921Y-980D01*
X478906Y-997D01*
X478889Y-1012D01*
X478874Y-1029D01*
X478857Y-1044D01*
X478842Y-1062D01*
X478802Y-1096D01*
X478758Y-1125D01*
X478729Y-1140D01*
X478727Y-1141D01*
X478713Y-1158D01*
X478695Y-1173D01*
X478680Y-1191D01*
X478663Y-1206D01*
X478649Y-1222D01*
X478648Y-1223D01*
X478631Y-1238D01*
X478616Y-1255D01*
X478598Y-1270D01*
X478583Y-1287D01*
X478566Y-1302D01*
X478551Y-1320D01*
X478534Y-1335D01*
X478519Y-1352D01*
X478502Y-1367D01*
X478487Y-1384D01*
X478469Y-1399D01*
X478454Y-1417D01*
X478437Y-1431D01*
X478422Y-1449D01*
X478405Y-1464D01*
X478391Y-1480D01*
X478390Y-1481D01*
X478373Y-1496D01*
X478358Y-1513D01*
X478340Y-1528D01*
X478325Y-1546D01*
X478308Y-1561D01*
X478293Y-1578D01*
X478276Y-1593D01*
X478261Y-1610D01*
X478244Y-1625D01*
X478229Y-1642D01*
X478211Y-1657D01*
X478196Y-1675D01*
X478179Y-1690D01*
X478164Y-1707D01*
X478147Y-1722D01*
X478132Y-1739D01*
X478115Y-1754D01*
X478099Y-1771D01*
X478082Y-1787D01*
X478067Y-1804D01*
X478050Y-1819D01*
X478035Y-1836D01*
X478018Y-1851D01*
X478003Y-1868D01*
X477985Y-1883D01*
X477971Y-1900D01*
X477953Y-1915D01*
X477938Y-1933D01*
X477921Y-1948D01*
X477906Y-1965D01*
X477889Y-1980D01*
X477874Y-1997D01*
X477856Y-2012D01*
X477841Y-2029D01*
X477824Y-2045D01*
X477821Y-2049D01*
X477809Y-2062D01*
X477792Y-2077D01*
X477777Y-2094D01*
X477760Y-2109D01*
X477745Y-2126D01*
X477728Y-2141D01*
X477712Y-2159D01*
X477695Y-2174D01*
X477680Y-2191D01*
X477663Y-2206D01*
X477648Y-2223D01*
X477631Y-2238D01*
X477616Y-2255D01*
X477598Y-2270D01*
D01*
X477583Y-2288D01*
X477566Y-2303D01*
X477551Y-2320D01*
X477534Y-2335D01*
X477519Y-2352D01*
X477502Y-2367D01*
X477487Y-2384D01*
X477469Y-2399D01*
X477454Y-2417D01*
X477437Y-2432D01*
X477427Y-2444D01*
X477422Y-2449D01*
X477405Y-2464D01*
X477390Y-2481D01*
X477373Y-2496D01*
X477357Y-2513D01*
X477340Y-2528D01*
X477325Y-2546D01*
X477308Y-2561D01*
X477293Y-2578D01*
X477276Y-2593D01*
X477261Y-2610D01*
X477244Y-2625D01*
X477230Y-2641D01*
X477228Y-2642D01*
X477211Y-2657D01*
X477196Y-2675D01*
X477179Y-2690D01*
X477164Y-2707D01*
X477147Y-2722D01*
X477132Y-2739D01*
X477115Y-2754D01*
X477114Y-2755D01*
X477099Y-2771D01*
X477082Y-2787D01*
X477075Y-2795D01*
X477067Y-2804D01*
X477050Y-2819D01*
X477035Y-2836D01*
X477018Y-2851D01*
X477003Y-2868D01*
X476986Y-2883D01*
X476970Y-2901D01*
X476953Y-2916D01*
X476938Y-2933D01*
X476921Y-2948D01*
X476906Y-2965D01*
X476889Y-2980D01*
X476874Y-2997D01*
X476856Y-3012D01*
X476841Y-3030D01*
X476824Y-3045D01*
X476809Y-3062D01*
X476792Y-3077D01*
X476777Y-3094D01*
X476760Y-3109D01*
X476745Y-3126D01*
X476727Y-3141D01*
X476712Y-3159D01*
X476695Y-3174D01*
X476681Y-3190D01*
X476680Y-3191D01*
X476663Y-3206D01*
X476648Y-3223D01*
X476608Y-3258D01*
X476565Y-3287D01*
X476535Y-3301D01*
X476534Y-3303D01*
X476519Y-3320D01*
X476502Y-3335D01*
X476486Y-3352D01*
X476469Y-3367D01*
X476454Y-3384D01*
X476437Y-3399D01*
X476422Y-3417D01*
X476405Y-3432D01*
X476390Y-3449D01*
X476372Y-3464D01*
X476357Y-3481D01*
X476340Y-3496D01*
X476325Y-3514D01*
X476308Y-3529D01*
X476293Y-3546D01*
X476276Y-3561D01*
X476261Y-3578D01*
X476243Y-3593D01*
X476228Y-3610D01*
X476211Y-3625D01*
X476197Y-3641D01*
X476196Y-3642D01*
X476179Y-3658D01*
X476164Y-3675D01*
X476147Y-3690D01*
X476145Y-3692D01*
X476131Y-3721D01*
X476102Y-3765D01*
X476082Y-3787D01*
X476081Y-3788D01*
X476066Y-3818D01*
X476060Y-3827D01*
X476057Y-3835D01*
X476055Y-3839D01*
Y-3843D01*
Y-3875D01*
Y-3907D01*
Y-3940D01*
Y-3972D01*
Y-4004D01*
Y-4037D01*
Y-4069D01*
Y-4101D01*
Y-4133D01*
Y-4166D01*
Y-4198D01*
Y-4230D01*
Y-4262D01*
Y-4295D01*
Y-4327D01*
Y-4359D01*
Y-4391D01*
Y-4424D01*
Y-4456D01*
Y-4488D01*
Y-4521D01*
Y-4553D01*
Y-4585D01*
Y-4617D01*
Y-4650D01*
Y-4682D01*
Y-4714D01*
Y-4746D01*
Y-4779D01*
Y-4811D01*
Y-4843D01*
Y-4875D01*
Y-4908D01*
Y-4940D01*
Y-4949D01*
X476066Y-4965D01*
X476081Y-4995D01*
X476095Y-5011D01*
X476102Y-5018D01*
X476116Y-5041D01*
X476130Y-5029D01*
X476145Y-5011D01*
X476162Y-4996D01*
X476178Y-4979D01*
X476195Y-4964D01*
X476210Y-4947D01*
X476227Y-4932D01*
X476242Y-4915D01*
X476259Y-4899D01*
X476274Y-4882D01*
X476292Y-4867D01*
X476307Y-4850D01*
X476315Y-4843D01*
X476324Y-4835D01*
X476339Y-4818D01*
X476356Y-4803D01*
X476371Y-4786D01*
X476388Y-4770D01*
X476404Y-4753D01*
X476421Y-4738D01*
X476436Y-4721D01*
X476453Y-4706D01*
X476468Y-4689D01*
X476485Y-4674D01*
X476500Y-4656D01*
X476517Y-4641D01*
X476533Y-4624D01*
X476550Y-4609D01*
X476565Y-4592D01*
X476580Y-4578D01*
X476582Y-4577D01*
X476597Y-4560D01*
X476636Y-4525D01*
X476680Y-4496D01*
X476709Y-4482D01*
X476711Y-4480D01*
X476726Y-4463D01*
X476743Y-4448D01*
X476758Y-4431D01*
X476776Y-4416D01*
X476791Y-4398D01*
X476808Y-4383D01*
X476823Y-4366D01*
X476839Y-4352D01*
X476840Y-4351D01*
X476855Y-4334D01*
X476872Y-4319D01*
X476887Y-4302D01*
X476905Y-4287D01*
X476920Y-4269D01*
X476937Y-4254D01*
X476952Y-4237D01*
X476969Y-4222D01*
X476984Y-4205D01*
X477001Y-4190D01*
X477016Y-4173D01*
X477034Y-4157D01*
X477049Y-4140D01*
X477066Y-4125D01*
X477081Y-4108D01*
X477098Y-4093D01*
X477113Y-4076D01*
X477130Y-4061D01*
X477145Y-4044D01*
X477153Y-4037D01*
X477163Y-4028D01*
X477178Y-4011D01*
X477195Y-3996D01*
X477210Y-3979D01*
X477227Y-3964D01*
X477242Y-3947D01*
X477259Y-3932D01*
X477275Y-3915D01*
X477292Y-3899D01*
X477307Y-3882D01*
X477324Y-3867D01*
X477339Y-3850D01*
X477356Y-3835D01*
X477371Y-3818D01*
X477371Y-3818D01*
X477389Y-3803D01*
X477404Y-3785D01*
X477421Y-3770D01*
X477436Y-3753D01*
X477453Y-3738D01*
X477468Y-3721D01*
X477468Y-3721D01*
X477485Y-3706D01*
X477500Y-3689D01*
X477518Y-3674D01*
X477533Y-3656D01*
X477550Y-3641D01*
X477565Y-3624D01*
X477582Y-3609D01*
X477597Y-3592D01*
X477614Y-3577D01*
X477629Y-3560D01*
X477647Y-3545D01*
X477662Y-3527D01*
X477679Y-3512D01*
X477694Y-3495D01*
X477702Y-3488D01*
X477711Y-3480D01*
X477726Y-3463D01*
X477743Y-3448D01*
X477759Y-3430D01*
X477776Y-3416D01*
X477791Y-3398D01*
X477808Y-3383D01*
X477823Y-3366D01*
X477840Y-3351D01*
X477840Y-3351D01*
X477855Y-3334D01*
X477872Y-3319D01*
X477887Y-3302D01*
X477888Y-3301D01*
X477905Y-3286D01*
X477920Y-3269D01*
X477933Y-3258D01*
X477937Y-3254D01*
X477952Y-3237D01*
X477969Y-3222D01*
X477984Y-3205D01*
X478001Y-3190D01*
X478017Y-3172D01*
X478019Y-3170D01*
X478034Y-3157D01*
X478049Y-3140D01*
X478066Y-3125D01*
X478081Y-3108D01*
X478098Y-3093D01*
X478113Y-3076D01*
X478131Y-3060D01*
X478146Y-3043D01*
X478163Y-3028D01*
X478178Y-3011D01*
X478195Y-2996D01*
X478210Y-2979D01*
X478227Y-2964D01*
X478242Y-2947D01*
X478260Y-2932D01*
X478275Y-2914D01*
X478292Y-2899D01*
X478307Y-2882D01*
X478324Y-2867D01*
X478339Y-2850D01*
X478356Y-2835D01*
X478371Y-2818D01*
X478389Y-2802D01*
X478404Y-2785D01*
X478421Y-2770D01*
X478436Y-2753D01*
X478449Y-2741D01*
X478453Y-2738D01*
X478468Y-2721D01*
X478485Y-2706D01*
X478501Y-2688D01*
X478518Y-2673D01*
X478533Y-2656D01*
X478550Y-2641D01*
X478565Y-2624D01*
X478582Y-2609D01*
X478597Y-2592D01*
X478615Y-2577D01*
X478629Y-2560D01*
X478647Y-2544D01*
X478662Y-2527D01*
X478662Y-2527D01*
X478679Y-2512D01*
X478694Y-2495D01*
X478710Y-2481D01*
X478711Y-2480D01*
X478726Y-2463D01*
X478744Y-2448D01*
X478759Y-2430D01*
X478776Y-2415D01*
X478791Y-2398D01*
X478808Y-2383D01*
X478823Y-2366D01*
X478840Y-2351D01*
X478855Y-2334D01*
X478872Y-2319D01*
X478888Y-2301D01*
X478905Y-2286D01*
X478920Y-2269D01*
X478937Y-2254D01*
X478952Y-2237D01*
X478968Y-2223D01*
X478969Y-2222D01*
X478984Y-2205D01*
X479000Y-2191D01*
X479002Y-2190D01*
X479017Y-2172D01*
X479034Y-2157D01*
X479049Y-2140D01*
X479066Y-2125D01*
X479081Y-2108D01*
X479098Y-2093D01*
X479113Y-2076D01*
X479131Y-2060D01*
X479146Y-2043D01*
X479163Y-2028D01*
X479178Y-2011D01*
X479195Y-1996D01*
X479210Y-1979D01*
X479227Y-1964D01*
X479243Y-1946D01*
X479256Y-1935D01*
X479260Y-1931D01*
X479275Y-1914D01*
X479292Y-1899D01*
X479307Y-1882D01*
X479324Y-1867D01*
X479339Y-1850D01*
X479379Y-1815D01*
X479422Y-1786D01*
X479452Y-1772D01*
X479453Y-1770D01*
X479468Y-1753D01*
X479486Y-1738D01*
X479501Y-1721D01*
X479518Y-1706D01*
X479533Y-1688D01*
X479550Y-1673D01*
X479565Y-1656D01*
X479582Y-1641D01*
X479597Y-1624D01*
X479605Y-1617D01*
X479615Y-1609D01*
X479630Y-1592D01*
X479647Y-1577D01*
X479662Y-1559D01*
X479679Y-1544D01*
X479694Y-1527D01*
X479711Y-1512D01*
X479726Y-1495D01*
X479744Y-1480D01*
X479759Y-1463D01*
X479776Y-1448D01*
X479791Y-1430D01*
X479808Y-1415D01*
X479823Y-1398D01*
X479840Y-1383D01*
X479855Y-1366D01*
X479855Y-1366D01*
X479873Y-1351D01*
X479888Y-1333D01*
X479901Y-1322D01*
X479905Y-1318D01*
X479920Y-1301D01*
X479937Y-1286D01*
X479952Y-1269D01*
X479970Y-1254D01*
X479985Y-1237D01*
X480002Y-1222D01*
X480017Y-1204D01*
X480034Y-1189D01*
X480049Y-1172D01*
X480066Y-1157D01*
X480081Y-1140D01*
X480098Y-1125D01*
X480099Y-1125D01*
X480114Y-1108D01*
X480131Y-1093D01*
X480146Y-1075D01*
X480163Y-1060D01*
X480178Y-1043D01*
X480195Y-1028D01*
X480210Y-1011D01*
X480228Y-996D01*
X480243Y-979D01*
X480260Y-964D01*
X480275Y-946D01*
X480292Y-931D01*
X480294Y-930D01*
X480308Y-900D01*
X480337Y-857D01*
X480343Y-850D01*
X480358Y-833D01*
X480372Y-804D01*
X480372Y-804D01*
X480379Y-794D01*
X480382Y-786D01*
X480405Y-739D01*
X480411Y-730D01*
X480414Y-722D01*
X480418Y-714D01*
X480419Y-694D01*
X480429Y-642D01*
X480446Y-593D01*
X480448Y-589D01*
Y-585D01*
Y-552D01*
Y-520D01*
Y-488D01*
Y-455D01*
Y-423D01*
Y-391D01*
Y-359D01*
Y-326D01*
Y-294D01*
Y-262D01*
Y-230D01*
Y-197D01*
Y-165D01*
Y-133D01*
Y-101D01*
Y-68D01*
Y-36D01*
Y-4D01*
Y28D01*
Y61D01*
Y93D01*
Y125D01*
Y157D01*
Y190D01*
Y222D01*
Y254D01*
Y286D01*
Y319D01*
Y351D01*
Y383D01*
Y416D01*
Y448D01*
Y480D01*
Y512D01*
Y545D01*
Y577D01*
Y609D01*
Y641D01*
Y674D01*
Y706D01*
Y738D01*
Y770D01*
Y803D01*
Y835D01*
Y867D01*
Y900D01*
Y932D01*
Y964D01*
Y996D01*
Y1029D01*
Y1061D01*
Y1093D01*
Y1125D01*
Y1158D01*
Y1190D01*
Y1222D01*
Y1254D01*
Y1287D01*
Y1319D01*
Y1351D01*
Y1383D01*
Y1416D01*
Y1448D01*
Y1480D01*
Y1512D01*
Y1545D01*
Y1577D01*
Y1609D01*
Y1641D01*
Y1674D01*
Y1706D01*
Y1738D01*
Y1770D01*
Y1803D01*
Y1835D01*
Y1867D01*
Y1900D01*
Y1932D01*
Y1964D01*
Y1996D01*
Y2029D01*
Y2061D01*
Y2093D01*
Y2125D01*
Y2158D01*
Y2190D01*
Y2222D01*
Y2254D01*
Y2287D01*
Y2319D01*
Y2351D01*
Y2383D01*
Y2416D01*
Y2448D01*
Y2480D01*
Y2513D01*
Y2545D01*
Y2577D01*
Y2609D01*
Y2642D01*
Y2674D01*
Y2706D01*
Y2738D01*
Y2771D01*
Y2803D01*
Y2835D01*
Y2867D01*
Y2900D01*
Y2932D01*
Y2964D01*
Y2997D01*
Y3029D01*
Y3061D01*
Y3093D01*
Y3125D01*
Y3158D01*
Y3190D01*
Y3222D01*
Y3255D01*
Y3287D01*
Y3319D01*
Y3351D01*
Y3384D01*
Y3416D01*
Y3448D01*
Y3480D01*
Y3513D01*
Y3545D01*
Y3577D01*
Y3609D01*
Y3642D01*
Y3674D01*
Y3706D01*
Y3739D01*
Y3771D01*
Y3803D01*
Y3835D01*
Y3867D01*
Y3900D01*
Y3932D01*
Y3964D01*
Y3997D01*
Y4029D01*
Y4061D01*
Y4093D01*
Y4126D01*
Y4158D01*
Y4190D01*
Y4222D01*
Y4255D01*
Y4287D01*
Y4319D01*
Y4352D01*
Y4384D01*
Y4416D01*
Y4448D01*
Y4481D01*
Y4513D01*
Y4545D01*
Y4577D01*
Y4610D01*
Y4642D01*
Y4674D01*
Y4706D01*
Y4739D01*
Y4771D01*
Y4803D01*
Y4835D01*
Y4868D01*
Y4900D01*
Y4932D01*
Y4964D01*
Y4997D01*
Y5029D01*
Y5061D01*
Y5094D01*
Y5126D01*
Y5158D01*
Y5190D01*
Y5223D01*
Y5255D01*
Y5287D01*
Y5319D01*
Y5352D01*
Y5384D01*
Y5416D01*
Y5448D01*
Y5481D01*
Y5513D01*
Y5545D01*
Y5577D01*
Y5610D01*
Y5642D01*
Y5674D01*
Y5706D01*
Y5739D01*
Y5771D01*
Y5803D01*
Y5835D01*
Y5868D01*
Y5900D01*
Y5932D01*
Y5965D01*
Y5997D01*
Y6029D01*
Y6061D01*
Y6094D01*
Y6126D01*
Y6158D01*
Y6190D01*
Y6223D01*
Y6255D01*
Y6287D01*
Y6319D01*
Y6352D01*
Y6384D01*
Y6416D01*
Y6448D01*
Y6481D01*
Y6513D01*
Y6545D01*
Y6577D01*
Y6610D01*
Y6642D01*
Y6674D01*
Y6707D01*
Y6739D01*
Y6771D01*
Y6803D01*
Y6836D01*
Y6868D01*
Y6900D01*
Y6932D01*
Y6965D01*
Y6997D01*
Y7029D01*
Y7062D01*
Y7094D01*
Y7126D01*
Y7158D01*
Y7191D01*
Y7223D01*
Y7255D01*
Y7287D01*
Y7320D01*
Y7352D01*
Y7384D01*
Y7416D01*
Y7449D01*
Y7481D01*
Y7513D01*
Y7545D01*
Y7578D01*
Y7610D01*
Y7642D01*
Y7674D01*
Y7707D01*
Y7739D01*
Y7771D01*
Y7803D01*
Y7836D01*
Y7868D01*
Y7900D01*
Y7932D01*
Y7965D01*
Y7997D01*
Y8029D01*
Y8062D01*
Y8094D01*
Y8126D01*
Y8158D01*
Y8191D01*
Y8223D01*
Y8255D01*
Y8287D01*
Y8320D01*
Y8352D01*
Y8384D01*
Y8416D01*
Y8449D01*
Y8481D01*
Y8513D01*
Y8546D01*
Y8578D01*
Y8610D01*
Y8642D01*
Y8675D01*
Y8707D01*
Y8739D01*
Y8771D01*
Y8804D01*
Y8836D01*
Y8868D01*
Y8900D01*
Y8933D01*
Y8965D01*
Y8997D01*
Y9029D01*
Y9062D01*
Y9094D01*
Y9126D01*
Y9131D01*
X480446Y9134D01*
X480429Y9184D01*
X480419Y9235D01*
X480418Y9250D01*
X480404Y9262D01*
X480389Y9279D01*
X480372Y9294D01*
X480360Y9308D01*
X480357Y9312D01*
X480339Y9327D01*
X480324Y9344D01*
X480307Y9359D01*
X480307Y9359D01*
X480292Y9376D01*
X480275Y9391D01*
X480260Y9408D01*
X480243Y9424D01*
X480228Y9441D01*
X480210Y9456D01*
X480195Y9473D01*
X480178Y9488D01*
X480163Y9505D01*
X480146Y9520D01*
X480131Y9537D01*
X480114Y9552D01*
X480098Y9570D01*
X480081Y9585D01*
X480066Y9602D01*
X480049Y9617D01*
X480034Y9634D01*
X480017Y9649D01*
X480002Y9667D01*
X479985Y9682D01*
X479969Y9699D01*
X479952Y9714D01*
X479937Y9731D01*
X479920Y9746D01*
X479905Y9763D01*
X479888Y9778D01*
X479873Y9796D01*
X479855Y9811D01*
X479840Y9828D01*
X479823Y9843D01*
X479808Y9860D01*
X479791Y9875D01*
X479776Y9892D01*
X479759Y9907D01*
X479744Y9925D01*
X479726Y9940D01*
X479711Y9957D01*
X479694Y9972D01*
X479679Y9989D01*
X479662Y10004D01*
X479649Y10018D01*
X479635Y10019D01*
X479584Y10029D01*
X479534Y10046D01*
X479530Y10048D01*
D02*
G37*
G36*
X462994Y-5407D02*
X462994Y-5408D01*
X462991Y-5416D01*
X462968Y-5463D01*
X462939Y-5507D01*
X462904Y-5546D01*
X462887Y-5561D01*
X462886Y-5563D01*
X462871Y-5592D01*
X462842Y-5636D01*
X462807Y-5675D01*
X462790Y-5690D01*
X462775Y-5707D01*
X462758Y-5722D01*
X462743Y-5740D01*
X462704Y-5774D01*
X462660Y-5803D01*
X462631Y-5818D01*
X462629Y-5819D01*
X462614Y-5836D01*
X462597Y-5851D01*
X462582Y-5869D01*
X462542Y-5903D01*
X462499Y-5932D01*
X462452Y-5956D01*
X462444Y-5958D01*
X462443Y-5959D01*
X462994D01*
Y-5940D01*
Y-5908D01*
Y-5875D01*
Y-5843D01*
Y-5811D01*
Y-5779D01*
Y-5746D01*
Y-5714D01*
Y-5682D01*
Y-5650D01*
Y-5617D01*
Y-5585D01*
Y-5553D01*
Y-5521D01*
Y-5488D01*
Y-5456D01*
Y-5424D01*
Y-5407D01*
D02*
G37*
G36*
X495145Y-1405D02*
X491089D01*
Y-1423D01*
Y-1456D01*
Y-1488D01*
Y-1520D01*
Y-1552D01*
Y-1585D01*
Y-1617D01*
Y-1649D01*
Y-1681D01*
Y-1714D01*
Y-1746D01*
Y-1778D01*
Y-1811D01*
Y-1843D01*
Y-1875D01*
Y-1907D01*
Y-1940D01*
Y-1972D01*
Y-2004D01*
Y-2036D01*
Y-2069D01*
Y-2101D01*
Y-2133D01*
Y-2165D01*
Y-2198D01*
Y-2230D01*
Y-2262D01*
Y-2294D01*
Y-2327D01*
Y-2359D01*
Y-2391D01*
Y-2424D01*
Y-2456D01*
Y-2488D01*
Y-2520D01*
Y-2553D01*
Y-2585D01*
Y-2617D01*
Y-2649D01*
Y-2682D01*
Y-2714D01*
Y-2746D01*
Y-2778D01*
Y-2811D01*
Y-2843D01*
Y-2875D01*
Y-2907D01*
Y-2940D01*
Y-2972D01*
Y-3004D01*
Y-3036D01*
Y-3069D01*
Y-3101D01*
Y-3133D01*
Y-3165D01*
Y-3198D01*
Y-3230D01*
Y-3262D01*
Y-3295D01*
Y-3327D01*
Y-3359D01*
Y-3391D01*
Y-3424D01*
Y-3456D01*
Y-3488D01*
Y-3520D01*
Y-3553D01*
Y-3585D01*
Y-3617D01*
Y-3650D01*
Y-3682D01*
Y-3714D01*
Y-3746D01*
Y-3779D01*
Y-3811D01*
Y-3843D01*
Y-3875D01*
Y-3907D01*
Y-3940D01*
Y-3972D01*
Y-4004D01*
Y-4037D01*
Y-4069D01*
Y-4101D01*
Y-4133D01*
Y-4166D01*
Y-4198D01*
Y-4230D01*
Y-4262D01*
Y-4295D01*
Y-4327D01*
Y-4359D01*
Y-4391D01*
Y-4424D01*
Y-4456D01*
Y-4488D01*
Y-4521D01*
Y-4553D01*
Y-4585D01*
Y-4617D01*
Y-4650D01*
Y-4682D01*
Y-4714D01*
Y-4746D01*
Y-4779D01*
Y-4811D01*
Y-4843D01*
Y-4875D01*
Y-4908D01*
Y-4940D01*
Y-4972D01*
Y-5004D01*
Y-5037D01*
Y-5069D01*
Y-5101D01*
Y-5133D01*
Y-5166D01*
Y-5198D01*
Y-5230D01*
Y-5263D01*
Y-5295D01*
Y-5327D01*
Y-5359D01*
Y-5392D01*
Y-5424D01*
Y-5456D01*
Y-5488D01*
Y-5521D01*
Y-5553D01*
Y-5585D01*
Y-5617D01*
Y-5650D01*
Y-5682D01*
Y-5714D01*
Y-5746D01*
Y-5779D01*
Y-5811D01*
Y-5843D01*
Y-5875D01*
Y-5908D01*
Y-5940D01*
Y-5972D01*
Y-6005D01*
Y-6037D01*
Y-6069D01*
Y-6101D01*
Y-6134D01*
Y-6166D01*
Y-6198D01*
Y-6230D01*
Y-6263D01*
Y-6295D01*
Y-6327D01*
Y-6359D01*
Y-6392D01*
Y-6424D01*
Y-6456D01*
Y-6488D01*
Y-6521D01*
Y-6553D01*
Y-6585D01*
Y-6617D01*
Y-6650D01*
Y-6682D01*
Y-6714D01*
Y-6747D01*
Y-6779D01*
Y-6811D01*
Y-6843D01*
Y-6876D01*
Y-6908D01*
Y-6940D01*
Y-6972D01*
Y-7005D01*
Y-7037D01*
Y-7069D01*
Y-7102D01*
Y-7134D01*
Y-7166D01*
Y-7198D01*
Y-7231D01*
Y-7263D01*
Y-7295D01*
Y-7327D01*
Y-7360D01*
Y-7392D01*
Y-7424D01*
Y-7456D01*
Y-7489D01*
Y-7521D01*
Y-7553D01*
Y-7585D01*
Y-7618D01*
Y-7636D01*
X495242D01*
X495245Y-7634D01*
X495295Y-7618D01*
X495346Y-7607D01*
X495361Y-7606D01*
X495373Y-7592D01*
X495391Y-7577D01*
X495406Y-7560D01*
X495423Y-7545D01*
X495438Y-7528D01*
X495455Y-7513D01*
X495470Y-7496D01*
X495487Y-7480D01*
X495502Y-7463D01*
X495520Y-7448D01*
X495535Y-7431D01*
X495552Y-7416D01*
X495567Y-7399D01*
X495584Y-7384D01*
X495599Y-7367D01*
X495616Y-7351D01*
X495632Y-7334D01*
X495649Y-7319D01*
X495664Y-7302D01*
X495681Y-7287D01*
X495696Y-7270D01*
X495713Y-7255D01*
X495728Y-7237D01*
X495741Y-7226D01*
X495746Y-7222D01*
X495760Y-7205D01*
X495778Y-7190D01*
X495793Y-7173D01*
X495801Y-7166D01*
X495810Y-7158D01*
X495825Y-7141D01*
X495842Y-7126D01*
X495857Y-7108D01*
X495865Y-7102D01*
X495875Y-7093D01*
X495890Y-7076D01*
X495907Y-7061D01*
X495922Y-7044D01*
X495938Y-7030D01*
X495939Y-7029D01*
X495954Y-7012D01*
X495971Y-6996D01*
X495986Y-6979D01*
X496004Y-6964D01*
X496019Y-6947D01*
X496036Y-6932D01*
X496051Y-6915D01*
X496068Y-6900D01*
X496083Y-6883D01*
X496100Y-6867D01*
X496115Y-6850D01*
X496133Y-6835D01*
X496146Y-6819D01*
X496158Y-6787D01*
X496161Y-6779D01*
X496163Y-6759D01*
X496173Y-6707D01*
X496190Y-6658D01*
X496192Y-6654D01*
Y-6650D01*
Y-6617D01*
Y-6585D01*
Y-6553D01*
Y-6521D01*
Y-6488D01*
Y-6456D01*
Y-6424D01*
Y-6392D01*
Y-6359D01*
Y-6327D01*
Y-6295D01*
Y-6263D01*
Y-6230D01*
Y-6198D01*
Y-6166D01*
Y-6134D01*
Y-6101D01*
Y-6069D01*
Y-6037D01*
Y-6005D01*
Y-5972D01*
Y-5940D01*
Y-5908D01*
Y-5875D01*
Y-5843D01*
Y-5811D01*
Y-5779D01*
Y-5746D01*
Y-5714D01*
Y-5682D01*
Y-5650D01*
Y-5617D01*
Y-5585D01*
Y-5553D01*
Y-5521D01*
Y-5488D01*
Y-5456D01*
Y-5424D01*
Y-5392D01*
Y-5359D01*
Y-5327D01*
Y-5295D01*
Y-5263D01*
Y-5230D01*
Y-5198D01*
Y-5166D01*
Y-5133D01*
Y-5101D01*
Y-5069D01*
Y-5037D01*
Y-5004D01*
Y-4972D01*
Y-4940D01*
Y-4908D01*
Y-4875D01*
Y-4843D01*
Y-4811D01*
Y-4779D01*
Y-4746D01*
Y-4714D01*
Y-4682D01*
Y-4650D01*
Y-4617D01*
Y-4585D01*
Y-4553D01*
Y-4521D01*
Y-4488D01*
Y-4456D01*
Y-4424D01*
Y-4391D01*
Y-4359D01*
Y-4327D01*
Y-4295D01*
Y-4262D01*
Y-4230D01*
Y-4198D01*
Y-4166D01*
Y-4133D01*
Y-4101D01*
Y-4069D01*
Y-4037D01*
Y-4004D01*
Y-3972D01*
Y-3940D01*
Y-3907D01*
Y-3875D01*
Y-3843D01*
Y-3811D01*
Y-3779D01*
Y-3746D01*
Y-3714D01*
Y-3682D01*
Y-3650D01*
Y-3617D01*
Y-3585D01*
Y-3553D01*
Y-3520D01*
Y-3488D01*
Y-3456D01*
Y-3424D01*
Y-3391D01*
Y-3359D01*
Y-3327D01*
Y-3295D01*
Y-3262D01*
Y-3230D01*
Y-3198D01*
Y-3165D01*
Y-3133D01*
Y-3101D01*
Y-3069D01*
Y-3036D01*
Y-3004D01*
Y-2972D01*
Y-2940D01*
Y-2907D01*
Y-2875D01*
Y-2843D01*
Y-2811D01*
Y-2778D01*
Y-2746D01*
Y-2714D01*
Y-2682D01*
Y-2649D01*
Y-2617D01*
Y-2585D01*
Y-2553D01*
Y-2520D01*
Y-2488D01*
Y-2456D01*
Y-2424D01*
Y-2391D01*
Y-2387D01*
X496190Y-2383D01*
X496173Y-2334D01*
X496163Y-2282D01*
X496162Y-2268D01*
X496148Y-2255D01*
X496133Y-2238D01*
X496115Y-2223D01*
X496100Y-2206D01*
X496083Y-2191D01*
X496068Y-2174D01*
X496051Y-2159D01*
X496036Y-2141D01*
X496019Y-2126D01*
X496004Y-2109D01*
X495986Y-2094D01*
X495971Y-2077D01*
X495954Y-2062D01*
X495939Y-2045D01*
X495922Y-2029D01*
X495907Y-2012D01*
X495890Y-1997D01*
X495890Y-1997D01*
X495875Y-1980D01*
X495857Y-1965D01*
X495846Y-1952D01*
X495842Y-1948D01*
X495825Y-1933D01*
X495810Y-1915D01*
X495793Y-1900D01*
X495778Y-1883D01*
X495760Y-1868D01*
X495745Y-1851D01*
X495728Y-1836D01*
X495713Y-1819D01*
X495696Y-1804D01*
X495681Y-1787D01*
X495664Y-1771D01*
X495649Y-1754D01*
X495632Y-1739D01*
X495616Y-1722D01*
X495599Y-1707D01*
X495584Y-1690D01*
X495567Y-1675D01*
X495552Y-1657D01*
X495535Y-1642D01*
X495520Y-1625D01*
X495502Y-1610D01*
X495487Y-1593D01*
X495470Y-1578D01*
X495469Y-1577D01*
X495455Y-1561D01*
X495438Y-1546D01*
X495423Y-1528D01*
X495406Y-1513D01*
X495391Y-1496D01*
X495373Y-1481D01*
X495358Y-1464D01*
X495357Y-1463D01*
X495342Y-1450D01*
X495310Y-1439D01*
X495306Y-1437D01*
X495302D01*
X495250Y-1434D01*
X495198Y-1424D01*
X495149Y-1407D01*
X495145Y-1405D01*
D02*
G37*
G36*
X488273D02*
X484218D01*
Y-1423D01*
Y-1456D01*
Y-1488D01*
Y-1520D01*
Y-1552D01*
Y-1585D01*
Y-1617D01*
Y-1649D01*
Y-1681D01*
Y-1714D01*
Y-1746D01*
Y-1778D01*
Y-1811D01*
Y-1843D01*
Y-1875D01*
Y-1907D01*
Y-1940D01*
Y-1972D01*
Y-2004D01*
Y-2036D01*
Y-2069D01*
Y-2101D01*
Y-2133D01*
Y-2165D01*
Y-2198D01*
Y-2230D01*
Y-2262D01*
Y-2294D01*
Y-2327D01*
D01*
Y-2359D01*
Y-2391D01*
Y-2424D01*
Y-2456D01*
Y-2488D01*
Y-2520D01*
Y-2553D01*
Y-2585D01*
Y-2617D01*
Y-2649D01*
Y-2682D01*
Y-2714D01*
Y-2746D01*
Y-2778D01*
Y-2811D01*
Y-2843D01*
Y-2875D01*
Y-2907D01*
Y-2940D01*
Y-2972D01*
Y-3004D01*
Y-3036D01*
Y-3069D01*
Y-3101D01*
Y-3133D01*
Y-3165D01*
D01*
Y-3198D01*
Y-3230D01*
Y-3262D01*
Y-3295D01*
Y-3327D01*
Y-3359D01*
Y-3391D01*
Y-3424D01*
Y-3456D01*
Y-3488D01*
Y-3520D01*
Y-3553D01*
Y-3585D01*
Y-3617D01*
Y-3650D01*
Y-3682D01*
Y-3714D01*
Y-3746D01*
Y-3779D01*
Y-3811D01*
Y-3843D01*
Y-3875D01*
Y-3907D01*
Y-3940D01*
Y-3972D01*
Y-4004D01*
Y-4037D01*
Y-4069D01*
Y-4101D01*
Y-4133D01*
Y-4166D01*
Y-4198D01*
Y-4230D01*
Y-4262D01*
Y-4295D01*
Y-4327D01*
Y-4359D01*
Y-4391D01*
Y-4424D01*
Y-4456D01*
Y-4488D01*
Y-4521D01*
Y-4553D01*
Y-4585D01*
Y-4617D01*
Y-4650D01*
Y-4682D01*
Y-4714D01*
Y-4746D01*
Y-4779D01*
Y-4811D01*
Y-4843D01*
Y-4875D01*
Y-4908D01*
Y-4940D01*
Y-4972D01*
Y-5004D01*
Y-5037D01*
Y-5069D01*
Y-5101D01*
Y-5133D01*
Y-5166D01*
Y-5198D01*
Y-5230D01*
Y-5263D01*
Y-5295D01*
Y-5327D01*
Y-5359D01*
Y-5392D01*
Y-5424D01*
Y-5456D01*
Y-5488D01*
Y-5521D01*
Y-5553D01*
Y-5585D01*
Y-5617D01*
Y-5650D01*
Y-5682D01*
Y-5714D01*
Y-5746D01*
Y-5779D01*
Y-5811D01*
Y-5843D01*
Y-5875D01*
Y-5908D01*
Y-5940D01*
Y-5972D01*
Y-6005D01*
Y-6037D01*
Y-6069D01*
Y-6101D01*
Y-6134D01*
Y-6166D01*
Y-6198D01*
Y-6230D01*
Y-6263D01*
Y-6295D01*
Y-6327D01*
Y-6359D01*
Y-6392D01*
Y-6424D01*
Y-6456D01*
Y-6488D01*
Y-6521D01*
Y-6553D01*
Y-6585D01*
Y-6617D01*
Y-6650D01*
Y-6682D01*
Y-6714D01*
Y-6747D01*
Y-6779D01*
Y-6811D01*
Y-6843D01*
Y-6876D01*
Y-6908D01*
Y-6940D01*
Y-6972D01*
Y-7005D01*
Y-7037D01*
Y-7069D01*
Y-7102D01*
Y-7134D01*
Y-7166D01*
Y-7198D01*
Y-7231D01*
Y-7263D01*
Y-7295D01*
Y-7327D01*
Y-7360D01*
Y-7392D01*
Y-7424D01*
Y-7456D01*
Y-7489D01*
Y-7521D01*
Y-7553D01*
Y-7585D01*
Y-7618D01*
Y-7636D01*
X485223D01*
Y-7618D01*
Y-7585D01*
Y-7553D01*
Y-7521D01*
Y-7489D01*
Y-7456D01*
Y-7424D01*
Y-7392D01*
Y-7360D01*
Y-7327D01*
Y-7295D01*
Y-7263D01*
Y-7231D01*
Y-7198D01*
Y-7166D01*
Y-7134D01*
Y-7102D01*
Y-7069D01*
Y-7037D01*
Y-7005D01*
Y-6972D01*
Y-6940D01*
Y-6908D01*
Y-6876D01*
Y-6843D01*
Y-6811D01*
Y-6779D01*
Y-6747D01*
Y-6714D01*
Y-6682D01*
Y-6650D01*
Y-6617D01*
Y-6585D01*
Y-6553D01*
Y-6521D01*
Y-6488D01*
Y-6456D01*
Y-6424D01*
Y-6392D01*
Y-6359D01*
Y-6327D01*
Y-6295D01*
Y-6291D01*
X485221Y-6287D01*
X485204Y-6237D01*
X485194Y-6186D01*
X485190Y-6134D01*
Y-6101D01*
X485194Y-6049D01*
X485204Y-5998D01*
X485221Y-5948D01*
X485223Y-5944D01*
Y-5940D01*
X485226Y-5888D01*
X485236Y-5836D01*
X485253Y-5787D01*
X485276Y-5740D01*
X485305Y-5696D01*
X485340Y-5657D01*
X485379Y-5622D01*
X485423Y-5593D01*
X485470Y-5570D01*
X485520Y-5553D01*
X485571Y-5543D01*
X485623Y-5539D01*
X486849D01*
X486902Y-5543D01*
X486953Y-5553D01*
X487003Y-5570D01*
X487050Y-5593D01*
X487093Y-5622D01*
X487133Y-5657D01*
X487167Y-5696D01*
X487196Y-5740D01*
X487220Y-5787D01*
X487222Y-5795D01*
X487229Y-5804D01*
X487243Y-5833D01*
X487264Y-5857D01*
X487293Y-5901D01*
X487317Y-5948D01*
X487319Y-5956D01*
X487326Y-5965D01*
X487340Y-5995D01*
X487361Y-6019D01*
X487390Y-6062D01*
X487413Y-6109D01*
X487416Y-6117D01*
X487422Y-6127D01*
X487446Y-6174D01*
X487448Y-6182D01*
X487455Y-6191D01*
X487469Y-6221D01*
X487490Y-6244D01*
X487519Y-6288D01*
X487542Y-6335D01*
X487545Y-6343D01*
X487551Y-6353D01*
X487566Y-6382D01*
X487587Y-6406D01*
X487616Y-6449D01*
X487639Y-6496D01*
X487642Y-6504D01*
X487648Y-6514D01*
X487660Y-6537D01*
X487663Y-6543D01*
X487684Y-6567D01*
X487713Y-6611D01*
X487736Y-6658D01*
X487739Y-6666D01*
X487745Y-6675D01*
X487768Y-6722D01*
X487771Y-6730D01*
X487777Y-6740D01*
X487790Y-6765D01*
X487792Y-6769D01*
X487813Y-6793D01*
X487842Y-6837D01*
X487865Y-6883D01*
X487868Y-6892D01*
X487874Y-6901D01*
X487888Y-6930D01*
X487909Y-6954D01*
X487939Y-6998D01*
X487962Y-7045D01*
X487964Y-7053D01*
X487971Y-7062D01*
X487985Y-7092D01*
X487994Y-7102D01*
X488006Y-7115D01*
X488035Y-7159D01*
X488059Y-7206D01*
X488061Y-7214D01*
X488068Y-7224D01*
X488082Y-7253D01*
X488103Y-7277D01*
X488132Y-7320D01*
X488155Y-7367D01*
X488158Y-7375D01*
X488164Y-7385D01*
X488188Y-7432D01*
X488190Y-7440D01*
X488197Y-7450D01*
X488211Y-7479D01*
X488232Y-7503D01*
X488261Y-7546D01*
X488284Y-7593D01*
X488287Y-7601D01*
X488293Y-7611D01*
X488306Y-7636D01*
X489331D01*
X489327Y-7627D01*
X489306Y-7604D01*
X489277Y-7560D01*
X489254Y-7513D01*
X489253Y-7511D01*
X489251Y-7505D01*
X489245Y-7496D01*
X489230Y-7466D01*
X489209Y-7442D01*
X489180Y-7399D01*
X489157Y-7352D01*
X489154Y-7344D01*
X489148Y-7334D01*
X489133Y-7305D01*
X489112Y-7281D01*
X489083Y-7237D01*
X489060Y-7190D01*
X489057Y-7182D01*
X489051Y-7173D01*
X489040Y-7150D01*
X489037Y-7144D01*
X489015Y-7120D01*
X488986Y-7076D01*
X488963Y-7029D01*
X488961Y-7021D01*
X488954Y-7012D01*
X488940Y-6982D01*
X488919Y-6958D01*
X488890Y-6915D01*
X488866Y-6868D01*
X488864Y-6860D01*
X488864Y-6860D01*
X488857Y-6850D01*
X488843Y-6821D01*
X488822Y-6797D01*
X488793Y-6753D01*
X488770Y-6706D01*
X488767Y-6698D01*
X488761Y-6689D01*
X488746Y-6660D01*
X488725Y-6636D01*
X488696Y-6592D01*
X488673Y-6545D01*
X488670Y-6537D01*
X488664Y-6528D01*
X488649Y-6498D01*
X488628Y-6474D01*
X488599Y-6431D01*
X488576Y-6384D01*
X488573Y-6376D01*
X488567Y-6366D01*
X488544Y-6319D01*
X488541Y-6311D01*
X488535Y-6302D01*
X488527Y-6287D01*
X488520Y-6273D01*
X488499Y-6249D01*
X488470Y-6205D01*
X488447Y-6158D01*
X488444Y-6150D01*
X488438Y-6140D01*
X488423Y-6111D01*
X488403Y-6087D01*
X488373Y-6044D01*
X488350Y-5997D01*
X488333Y-5947D01*
X488323Y-5896D01*
X488320Y-5843D01*
Y-5811D01*
Y-5779D01*
X488323Y-5726D01*
X488333Y-5675D01*
X488350Y-5625D01*
X488373Y-5578D01*
X488403Y-5535D01*
X488437Y-5495D01*
X488454Y-5480D01*
X488469Y-5463D01*
X488487Y-5448D01*
X488502Y-5431D01*
X488519Y-5416D01*
X488534Y-5398D01*
X488551Y-5384D01*
X488566Y-5366D01*
X488583Y-5351D01*
X488598Y-5334D01*
X488616Y-5319D01*
X488631Y-5302D01*
X488639Y-5295D01*
X488648Y-5287D01*
X488663Y-5269D01*
X488671Y-5263D01*
X488680Y-5254D01*
X488695Y-5237D01*
X488712Y-5222D01*
X488728Y-5205D01*
X488745Y-5190D01*
X488760Y-5173D01*
X488768Y-5166D01*
X488777Y-5158D01*
X488792Y-5140D01*
X488809Y-5125D01*
X488824Y-5108D01*
X488841Y-5093D01*
X488857Y-5076D01*
X488864Y-5069D01*
X488874Y-5061D01*
X488889Y-5044D01*
X488906Y-5029D01*
X488921Y-5011D01*
X488938Y-4997D01*
X488938Y-4996D01*
X488953Y-4979D01*
X488971Y-4964D01*
X488986Y-4947D01*
X488993Y-4940D01*
X489003Y-4932D01*
X489018Y-4915D01*
X489035Y-4899D01*
X489050Y-4882D01*
X489067Y-4867D01*
X489082Y-4850D01*
X489100Y-4835D01*
X489101Y-4833D01*
X489115Y-4804D01*
X489145Y-4760D01*
X489179Y-4721D01*
X489196Y-4706D01*
X489211Y-4689D01*
X489228Y-4674D01*
X489244Y-4656D01*
X489261Y-4641D01*
X489276Y-4624D01*
X489293Y-4609D01*
X489294Y-4608D01*
X489309Y-4578D01*
X489315Y-4569D01*
X489318Y-4561D01*
X489320Y-4557D01*
Y-4553D01*
Y-4521D01*
Y-4488D01*
Y-4456D01*
Y-4424D01*
Y-4391D01*
Y-4359D01*
Y-4327D01*
Y-4295D01*
Y-4262D01*
Y-4230D01*
Y-4198D01*
Y-4166D01*
Y-4133D01*
Y-4101D01*
Y-4069D01*
Y-4037D01*
Y-4004D01*
Y-3972D01*
Y-3940D01*
Y-3907D01*
Y-3875D01*
Y-3843D01*
Y-3811D01*
Y-3779D01*
Y-3746D01*
Y-3714D01*
Y-3682D01*
Y-3650D01*
Y-3617D01*
Y-3585D01*
Y-3553D01*
Y-3520D01*
Y-3488D01*
Y-3456D01*
Y-3424D01*
Y-3391D01*
Y-3359D01*
Y-3327D01*
Y-3295D01*
Y-3262D01*
Y-3230D01*
Y-3198D01*
Y-3165D01*
D01*
Y-3133D01*
Y-3101D01*
Y-3069D01*
Y-3036D01*
Y-3004D01*
Y-2972D01*
Y-2940D01*
Y-2907D01*
Y-2875D01*
Y-2843D01*
Y-2811D01*
Y-2778D01*
Y-2746D01*
Y-2714D01*
Y-2682D01*
Y-2649D01*
Y-2617D01*
Y-2585D01*
Y-2553D01*
Y-2520D01*
Y-2488D01*
Y-2456D01*
Y-2424D01*
Y-2391D01*
Y-2359D01*
Y-2327D01*
D01*
Y-2322D01*
X489318Y-2319D01*
X489301Y-2269D01*
X489296Y-2242D01*
X489295Y-2240D01*
X489293Y-2238D01*
X489276Y-2223D01*
X489261Y-2206D01*
X489244Y-2191D01*
X489229Y-2174D01*
X489211Y-2159D01*
X489196Y-2141D01*
X489179Y-2126D01*
X489164Y-2109D01*
X489147Y-2094D01*
X489132Y-2077D01*
X489115Y-2062D01*
X489100Y-2045D01*
X489082Y-2029D01*
X489067Y-2012D01*
X489050Y-1997D01*
X489035Y-1980D01*
X489018Y-1965D01*
X489003Y-1948D01*
X488986Y-1933D01*
X488971Y-1915D01*
X488953Y-1900D01*
X488938Y-1883D01*
X488921Y-1868D01*
X488906Y-1851D01*
X488889Y-1836D01*
X488874Y-1819D01*
X488857Y-1804D01*
X488841Y-1787D01*
X488824Y-1771D01*
X488809Y-1754D01*
X488792Y-1739D01*
X488777Y-1722D01*
X488760Y-1707D01*
X488745Y-1690D01*
X488728Y-1675D01*
X488712Y-1657D01*
X488695Y-1642D01*
X488680Y-1625D01*
X488663Y-1610D01*
X488648Y-1593D01*
X488631Y-1578D01*
X488616Y-1561D01*
X488598Y-1546D01*
X488583Y-1528D01*
X488566Y-1513D01*
X488551Y-1496D01*
X488534Y-1481D01*
X488519Y-1464D01*
X488517Y-1462D01*
X488514Y-1461D01*
X488488Y-1456D01*
X488438Y-1439D01*
X488435Y-1437D01*
X488430D01*
X488378Y-1434D01*
X488327Y-1424D01*
X488277Y-1407D01*
X488273Y-1405D01*
D02*
G37*
G36*
X476014D02*
X472456D01*
X472453Y-1407D01*
X472403Y-1424D01*
X472376Y-1429D01*
X472356Y-1439D01*
X472306Y-1456D01*
X472280Y-1461D01*
X472277Y-1462D01*
X472275Y-1464D01*
X472260Y-1481D01*
X472243Y-1496D01*
X472229Y-1512D01*
X472228Y-1513D01*
X472211Y-1528D01*
X472197Y-1544D01*
X472196Y-1546D01*
X472178Y-1561D01*
X472164Y-1577D01*
X472163Y-1578D01*
X472146Y-1593D01*
X472131Y-1610D01*
X472114Y-1625D01*
X472100Y-1641D01*
X472099Y-1642D01*
X472082Y-1657D01*
X472067Y-1675D01*
X472049Y-1690D01*
X472034Y-1707D01*
X472017Y-1722D01*
X472002Y-1739D01*
X471985Y-1754D01*
X471970Y-1771D01*
X471953Y-1787D01*
X471938Y-1804D01*
X471920Y-1819D01*
X471905Y-1836D01*
X471888Y-1851D01*
X471873Y-1868D01*
X471856Y-1883D01*
X471841Y-1900D01*
X471824Y-1915D01*
X471808Y-1933D01*
X471791Y-1948D01*
X471776Y-1965D01*
X471759Y-1980D01*
X471744Y-1997D01*
X471727Y-2012D01*
X471712Y-2029D01*
X471695Y-2045D01*
X471680Y-2061D01*
X471679Y-2062D01*
X471662Y-2077D01*
X471647Y-2094D01*
X471630Y-2109D01*
X471615Y-2126D01*
X471598Y-2141D01*
X471583Y-2159D01*
X471565Y-2174D01*
X471550Y-2191D01*
X471533Y-2206D01*
X471518Y-2223D01*
X471504Y-2235D01*
X471503Y-2250D01*
X471493Y-2301D01*
X471476Y-2351D01*
X471474Y-2355D01*
Y-2359D01*
Y-2391D01*
Y-2424D01*
Y-2456D01*
Y-2488D01*
Y-2520D01*
Y-2553D01*
Y-2585D01*
Y-2617D01*
Y-2649D01*
Y-2682D01*
Y-2714D01*
Y-2746D01*
Y-2778D01*
Y-2811D01*
Y-2843D01*
Y-2875D01*
Y-2907D01*
Y-2940D01*
Y-2972D01*
Y-3004D01*
Y-3036D01*
Y-3069D01*
Y-3101D01*
Y-3133D01*
Y-3165D01*
Y-3198D01*
Y-3230D01*
Y-3262D01*
Y-3295D01*
Y-3327D01*
Y-3359D01*
Y-3391D01*
Y-3424D01*
Y-3456D01*
Y-3488D01*
Y-3520D01*
Y-3553D01*
Y-3585D01*
Y-3617D01*
Y-3650D01*
Y-3682D01*
Y-3714D01*
Y-3746D01*
Y-3779D01*
Y-3811D01*
Y-3843D01*
Y-3875D01*
Y-3907D01*
Y-3940D01*
Y-3972D01*
Y-4004D01*
Y-4037D01*
Y-4069D01*
Y-4101D01*
Y-4133D01*
Y-4166D01*
Y-4198D01*
Y-4230D01*
Y-4262D01*
Y-4295D01*
Y-4327D01*
Y-4359D01*
Y-4391D01*
Y-4424D01*
Y-4456D01*
Y-4488D01*
Y-4521D01*
Y-4553D01*
Y-4585D01*
Y-4617D01*
Y-4650D01*
Y-4682D01*
Y-4714D01*
Y-4746D01*
Y-4779D01*
Y-4811D01*
Y-4843D01*
Y-4875D01*
Y-4908D01*
Y-4940D01*
Y-4972D01*
Y-5004D01*
Y-5037D01*
Y-5069D01*
Y-5101D01*
Y-5133D01*
Y-5166D01*
Y-5198D01*
Y-5230D01*
Y-5263D01*
Y-5295D01*
Y-5327D01*
Y-5359D01*
Y-5392D01*
Y-5424D01*
Y-5456D01*
Y-5488D01*
Y-5521D01*
Y-5553D01*
Y-5585D01*
Y-5617D01*
Y-5650D01*
Y-5682D01*
Y-5714D01*
Y-5746D01*
Y-5779D01*
Y-5811D01*
Y-5843D01*
Y-5875D01*
Y-5908D01*
Y-5940D01*
Y-5972D01*
Y-6005D01*
Y-6037D01*
Y-6069D01*
Y-6101D01*
Y-6134D01*
Y-6166D01*
Y-6198D01*
Y-6230D01*
Y-6263D01*
Y-6295D01*
Y-6327D01*
Y-6359D01*
Y-6392D01*
Y-6424D01*
Y-6456D01*
Y-6488D01*
Y-6521D01*
Y-6553D01*
Y-6585D01*
Y-6617D01*
Y-6650D01*
Y-6682D01*
Y-6714D01*
Y-6719D01*
X471476Y-6722D01*
X471493Y-6772D01*
X471498Y-6798D01*
X471499Y-6801D01*
X471501Y-6803D01*
X471518Y-6818D01*
X471533Y-6835D01*
X471550Y-6850D01*
X471565Y-6867D01*
X471583Y-6883D01*
X471598Y-6900D01*
X471615Y-6915D01*
X471630Y-6932D01*
X471647Y-6947D01*
X471662Y-6964D01*
X471679Y-6979D01*
X471695Y-6996D01*
X471712Y-7012D01*
X471727Y-7029D01*
X471744Y-7044D01*
X471759Y-7061D01*
X471776Y-7076D01*
X471791Y-7093D01*
X471801Y-7102D01*
X471808Y-7108D01*
X471824Y-7126D01*
X471841Y-7141D01*
X471856Y-7158D01*
X471873Y-7173D01*
X471873Y-7173D01*
X471888Y-7190D01*
X471905Y-7205D01*
X471920Y-7222D01*
X471921Y-7223D01*
X471938Y-7237D01*
X471953Y-7255D01*
X471970Y-7270D01*
X471985Y-7287D01*
X472002Y-7302D01*
X472017Y-7319D01*
X472034Y-7334D01*
X472049Y-7351D01*
X472067Y-7367D01*
X472082Y-7384D01*
X472099Y-7399D01*
X472114Y-7416D01*
X472131Y-7431D01*
X472146Y-7448D01*
X472163Y-7463D01*
X472178Y-7480D01*
X472196Y-7496D01*
X472211Y-7513D01*
X472228Y-7528D01*
X472243Y-7545D01*
X472260Y-7560D01*
X472275Y-7577D01*
X472292Y-7592D01*
X472307Y-7609D01*
X472309Y-7611D01*
X472312Y-7612D01*
X472338Y-7618D01*
X472388Y-7634D01*
X472392Y-7636D01*
X476028D01*
Y-7618D01*
Y-7585D01*
Y-7553D01*
Y-7521D01*
Y-7489D01*
Y-7456D01*
Y-7424D01*
Y-7392D01*
Y-7360D01*
Y-7327D01*
Y-7295D01*
Y-7263D01*
Y-7231D01*
Y-7198D01*
Y-7166D01*
Y-7134D01*
Y-7102D01*
Y-7069D01*
Y-7037D01*
Y-7005D01*
Y-6972D01*
Y-6940D01*
Y-6908D01*
Y-6876D01*
Y-6843D01*
Y-6811D01*
Y-6779D01*
Y-6747D01*
Y-6728D01*
X472944D01*
X472892Y-6725D01*
X472841Y-6714D01*
X472791Y-6697D01*
X472744Y-6674D01*
X472735Y-6668D01*
X472727Y-6665D01*
X472680Y-6642D01*
X472636Y-6613D01*
X472597Y-6578D01*
X472562Y-6539D01*
X472533Y-6495D01*
X472510Y-6448D01*
X472507Y-6440D01*
X472501Y-6431D01*
X472477Y-6384D01*
X472461Y-6334D01*
X472450Y-6283D01*
X472447Y-6230D01*
Y-6198D01*
Y-6166D01*
Y-6134D01*
Y-6101D01*
Y-6069D01*
Y-6037D01*
Y-6005D01*
Y-5972D01*
Y-5940D01*
Y-5908D01*
Y-5875D01*
Y-5843D01*
Y-5811D01*
Y-5779D01*
Y-5746D01*
Y-5714D01*
Y-5682D01*
Y-5650D01*
Y-5617D01*
Y-5585D01*
Y-5553D01*
Y-5521D01*
Y-5488D01*
Y-5456D01*
Y-5424D01*
Y-5392D01*
Y-5359D01*
Y-5327D01*
Y-5295D01*
Y-5263D01*
Y-5230D01*
Y-5198D01*
Y-5166D01*
Y-5133D01*
Y-5101D01*
Y-5069D01*
Y-5037D01*
Y-5004D01*
Y-4972D01*
Y-4940D01*
Y-4908D01*
Y-4875D01*
Y-4843D01*
Y-4811D01*
Y-4779D01*
Y-4746D01*
Y-4714D01*
Y-4682D01*
Y-4650D01*
Y-4617D01*
Y-4585D01*
Y-4553D01*
Y-4521D01*
Y-4488D01*
Y-4456D01*
Y-4424D01*
Y-4391D01*
Y-4359D01*
Y-4327D01*
Y-4295D01*
Y-4262D01*
Y-4230D01*
Y-4198D01*
Y-4166D01*
Y-4133D01*
Y-4101D01*
Y-4069D01*
Y-4037D01*
Y-4004D01*
Y-3972D01*
Y-3940D01*
Y-3907D01*
Y-3875D01*
Y-3843D01*
Y-3811D01*
Y-3779D01*
Y-3746D01*
Y-3714D01*
Y-3682D01*
Y-3650D01*
Y-3617D01*
Y-3585D01*
Y-3553D01*
Y-3520D01*
Y-3488D01*
Y-3456D01*
Y-3424D01*
Y-3391D01*
Y-3359D01*
Y-3327D01*
Y-3295D01*
Y-3262D01*
Y-3230D01*
Y-3198D01*
Y-3165D01*
Y-3133D01*
Y-3101D01*
Y-3069D01*
Y-3036D01*
Y-3004D01*
Y-2972D01*
Y-2940D01*
Y-2907D01*
Y-2875D01*
Y-2843D01*
Y-2811D01*
X472450Y-2758D01*
X472461Y-2707D01*
X472477Y-2657D01*
X472501Y-2610D01*
X472530Y-2567D01*
X472564Y-2527D01*
X472581Y-2512D01*
X472597Y-2495D01*
X472614Y-2480D01*
X472629Y-2463D01*
X472668Y-2428D01*
X472712Y-2399D01*
X472759Y-2376D01*
X472809Y-2359D01*
X472860Y-2349D01*
X472912Y-2345D01*
X475949D01*
X475953Y-2344D01*
X476003Y-2327D01*
X476028Y-2322D01*
Y-2294D01*
Y-2262D01*
Y-2230D01*
Y-2198D01*
Y-2165D01*
Y-2133D01*
Y-2101D01*
Y-2069D01*
Y-2036D01*
Y-2004D01*
Y-1972D01*
Y-1940D01*
Y-1907D01*
Y-1875D01*
Y-1843D01*
Y-1811D01*
Y-1778D01*
Y-1746D01*
Y-1714D01*
Y-1681D01*
Y-1649D01*
Y-1617D01*
Y-1585D01*
Y-1552D01*
Y-1520D01*
Y-1488D01*
Y-1456D01*
Y-1423D01*
Y-1410D01*
X476017Y-1407D01*
X476014Y-1405D01*
D02*
G37*
G36*
X462994Y-7567D02*
X462488D01*
X462502Y-7579D01*
X462531Y-7593D01*
X462574Y-7622D01*
X462614Y-7657D01*
X462629Y-7674D01*
X462646Y-7689D01*
X462661Y-7706D01*
X462678Y-7721D01*
X462694Y-7739D01*
X462711Y-7754D01*
X462726Y-7771D01*
X462743Y-7786D01*
X462758Y-7803D01*
X462775Y-7818D01*
X462790Y-7835D01*
X462807Y-7850D01*
X462823Y-7868D01*
X462840Y-7883D01*
X462855Y-7900D01*
X462872Y-7915D01*
X462907Y-7954D01*
X462936Y-7998D01*
X462950Y-8027D01*
X462971Y-8051D01*
X462994Y-8086D01*
Y-8069D01*
Y-8037D01*
Y-8005D01*
Y-7972D01*
Y-7940D01*
Y-7908D01*
Y-7876D01*
Y-7843D01*
Y-7811D01*
Y-7779D01*
Y-7747D01*
Y-7714D01*
Y-7682D01*
Y-7650D01*
Y-7618D01*
Y-7585D01*
Y-7567D01*
D02*
G37*
G36*
Y-9775D02*
X462982Y-9789D01*
X462968Y-9818D01*
X462939Y-9862D01*
X462918Y-9886D01*
X462903Y-9915D01*
X462874Y-9959D01*
X462840Y-9998D01*
X462823Y-10013D01*
X462807Y-10030D01*
X462790Y-10046D01*
X462775Y-10063D01*
X462758Y-10078D01*
X462743Y-10095D01*
X462726Y-10110D01*
X462711Y-10127D01*
X462693Y-10142D01*
X462678Y-10159D01*
X462639Y-10194D01*
X462595Y-10223D01*
X462566Y-10238D01*
X462542Y-10259D01*
X462499Y-10288D01*
X462469Y-10302D01*
X462456Y-10314D01*
X462994D01*
Y-10295D01*
Y-10263D01*
Y-10231D01*
Y-10199D01*
Y-10166D01*
Y-10134D01*
Y-10102D01*
Y-10069D01*
Y-10037D01*
Y-10005D01*
Y-9973D01*
Y-9940D01*
Y-9908D01*
Y-9876D01*
Y-9844D01*
Y-9811D01*
Y-9779D01*
Y-9775D01*
D02*
G37*
G36*
Y-11922D02*
X462475D01*
X462510Y-11945D01*
X462534Y-11966D01*
X462563Y-11981D01*
X462607Y-12010D01*
X462646Y-12044D01*
X462661Y-12062D01*
X462678Y-12077D01*
X462694Y-12094D01*
X462711Y-12109D01*
X462726Y-12126D01*
X462743Y-12141D01*
X462758Y-12158D01*
X462775Y-12173D01*
X462790Y-12191D01*
X462807Y-12206D01*
X462823Y-12223D01*
X462840Y-12238D01*
X462855Y-12255D01*
X462872Y-12270D01*
X462907Y-12310D01*
X462936Y-12353D01*
X462950Y-12383D01*
X462971Y-12406D01*
X462994Y-12441D01*
Y-12425D01*
Y-12392D01*
Y-12360D01*
Y-12328D01*
Y-12296D01*
Y-12263D01*
Y-12231D01*
Y-12199D01*
Y-12167D01*
Y-12134D01*
Y-12102D01*
Y-12070D01*
Y-12037D01*
Y-12005D01*
Y-11973D01*
Y-11941D01*
Y-11922D01*
D02*
G37*
G36*
Y-14150D02*
X462971Y-14185D01*
X462950Y-14209D01*
X462936Y-14238D01*
X462907Y-14282D01*
X462872Y-14321D01*
X462855Y-14336D01*
X462840Y-14354D01*
X462822Y-14368D01*
X462807Y-14386D01*
X462790Y-14401D01*
X462775Y-14418D01*
X462758Y-14433D01*
X462743Y-14450D01*
X462726Y-14465D01*
X462711Y-14482D01*
X462694Y-14498D01*
X462678Y-14515D01*
X462661Y-14530D01*
X462646Y-14547D01*
X462607Y-14582D01*
X462563Y-14611D01*
X462534Y-14625D01*
X462510Y-14646D01*
X462475Y-14669D01*
X462994D01*
Y-14651D01*
Y-14618D01*
Y-14586D01*
Y-14554D01*
Y-14522D01*
Y-14489D01*
Y-14457D01*
Y-14425D01*
Y-14393D01*
Y-14360D01*
Y-14328D01*
Y-14296D01*
Y-14264D01*
Y-14231D01*
Y-14199D01*
Y-14167D01*
Y-14150D01*
D02*
G37*
%LPD*%
G36*
X494806Y-2316D02*
X494857Y-2327D01*
X494907Y-2344D01*
X494954Y-2367D01*
X494964Y-2373D01*
X494971Y-2376D01*
X495018Y-2399D01*
X495062Y-2428D01*
X495101Y-2463D01*
X495136Y-2502D01*
X495165Y-2546D01*
X495188Y-2593D01*
X495205Y-2642D01*
X495216Y-2694D01*
X495219Y-2746D01*
Y-2778D01*
Y-2811D01*
Y-2843D01*
Y-2875D01*
Y-2907D01*
Y-2940D01*
Y-2972D01*
Y-3004D01*
Y-3036D01*
Y-3069D01*
Y-3101D01*
Y-3133D01*
Y-3165D01*
Y-3198D01*
Y-3230D01*
Y-3262D01*
Y-3295D01*
Y-3327D01*
Y-3359D01*
Y-3391D01*
Y-3424D01*
Y-3456D01*
Y-3488D01*
Y-3520D01*
Y-3553D01*
Y-3585D01*
Y-3617D01*
Y-3650D01*
Y-3682D01*
Y-3714D01*
Y-3746D01*
Y-3779D01*
Y-3811D01*
Y-3843D01*
Y-3875D01*
Y-3907D01*
Y-3940D01*
Y-3972D01*
Y-4004D01*
Y-4037D01*
Y-4069D01*
Y-4101D01*
Y-4133D01*
Y-4166D01*
Y-4198D01*
Y-4230D01*
Y-4262D01*
Y-4295D01*
Y-4327D01*
Y-4359D01*
Y-4391D01*
Y-4424D01*
Y-4456D01*
Y-4488D01*
Y-4521D01*
Y-4553D01*
Y-4585D01*
Y-4617D01*
Y-4650D01*
Y-4682D01*
Y-4714D01*
Y-4746D01*
Y-4779D01*
Y-4811D01*
Y-4843D01*
Y-4875D01*
Y-4908D01*
Y-4940D01*
Y-4972D01*
Y-5004D01*
Y-5037D01*
Y-5069D01*
Y-5101D01*
Y-5133D01*
Y-5166D01*
Y-5198D01*
Y-5230D01*
Y-5263D01*
Y-5295D01*
Y-5327D01*
Y-5359D01*
Y-5392D01*
Y-5424D01*
Y-5456D01*
Y-5488D01*
Y-5521D01*
Y-5553D01*
Y-5585D01*
Y-5617D01*
Y-5650D01*
Y-5682D01*
Y-5714D01*
Y-5746D01*
Y-5779D01*
Y-5811D01*
Y-5843D01*
Y-5875D01*
Y-5908D01*
Y-5940D01*
Y-5972D01*
Y-6005D01*
Y-6037D01*
Y-6069D01*
Y-6101D01*
Y-6134D01*
Y-6166D01*
Y-6198D01*
Y-6230D01*
Y-6263D01*
Y-6295D01*
Y-6327D01*
X495216Y-6380D01*
X495205Y-6431D01*
X495188Y-6481D01*
X495165Y-6528D01*
X495136Y-6571D01*
X495101Y-6611D01*
X495062Y-6645D01*
X495018Y-6674D01*
X494971Y-6697D01*
X494922Y-6714D01*
X494870Y-6725D01*
X494818Y-6728D01*
X492463D01*
X492411Y-6725D01*
X492359Y-6714D01*
X492310Y-6697D01*
X492263Y-6674D01*
X492219Y-6645D01*
X492179Y-6611D01*
X492145Y-6571D01*
X492116Y-6528D01*
X492093Y-6481D01*
X492076Y-6431D01*
X492065Y-6380D01*
X492062Y-6327D01*
Y-6295D01*
Y-6263D01*
Y-6230D01*
Y-6198D01*
Y-6166D01*
Y-6134D01*
Y-6101D01*
Y-6069D01*
Y-6037D01*
Y-6005D01*
Y-5972D01*
Y-5940D01*
Y-5908D01*
Y-5875D01*
Y-5843D01*
Y-5811D01*
Y-5779D01*
Y-5746D01*
Y-5714D01*
Y-5682D01*
Y-5650D01*
Y-5617D01*
Y-5585D01*
Y-5553D01*
Y-5521D01*
Y-5488D01*
Y-5456D01*
Y-5424D01*
Y-5392D01*
Y-5359D01*
Y-5327D01*
Y-5295D01*
Y-5263D01*
Y-5230D01*
Y-5198D01*
Y-5166D01*
Y-5133D01*
Y-5101D01*
Y-5069D01*
Y-5037D01*
Y-5004D01*
Y-4972D01*
Y-4940D01*
Y-4908D01*
Y-4875D01*
Y-4843D01*
Y-4811D01*
Y-4779D01*
Y-4746D01*
Y-4714D01*
Y-4682D01*
Y-4650D01*
Y-4617D01*
Y-4585D01*
Y-4553D01*
Y-4521D01*
Y-4488D01*
Y-4456D01*
Y-4424D01*
Y-4391D01*
Y-4359D01*
Y-4327D01*
Y-4295D01*
Y-4262D01*
Y-4230D01*
Y-4198D01*
Y-4166D01*
Y-4133D01*
Y-4101D01*
Y-4069D01*
Y-4037D01*
Y-4004D01*
Y-3972D01*
Y-3940D01*
Y-3907D01*
Y-3875D01*
Y-3843D01*
Y-3811D01*
Y-3779D01*
Y-3746D01*
Y-3714D01*
Y-3682D01*
Y-3650D01*
Y-3617D01*
Y-3585D01*
Y-3553D01*
Y-3520D01*
Y-3488D01*
Y-3456D01*
Y-3424D01*
Y-3391D01*
Y-3359D01*
Y-3327D01*
Y-3295D01*
Y-3262D01*
Y-3230D01*
Y-3198D01*
Y-3165D01*
Y-3133D01*
Y-3101D01*
Y-3069D01*
Y-3036D01*
Y-3004D01*
Y-2972D01*
Y-2940D01*
Y-2907D01*
Y-2875D01*
Y-2843D01*
Y-2811D01*
Y-2778D01*
Y-2746D01*
X492065Y-2694D01*
X492076Y-2642D01*
X492093Y-2593D01*
X492116Y-2546D01*
X492145Y-2502D01*
X492179Y-2463D01*
X492197Y-2448D01*
X492212Y-2430D01*
X492251Y-2396D01*
X492295Y-2367D01*
X492342Y-2344D01*
X492391Y-2327D01*
X492443Y-2316D01*
X492495Y-2313D01*
X492527D01*
X492580Y-2316D01*
X492631Y-2327D01*
X492681Y-2344D01*
X492684Y-2345D01*
X494467D01*
X494471Y-2344D01*
X494521Y-2327D01*
X494572Y-2316D01*
X494625Y-2313D01*
X494657D01*
X494689Y-2315D01*
X494721Y-2313D01*
X494754D01*
X494806Y-2316D01*
D02*
G37*
G36*
X487999Y-2252D02*
X488050Y-2262D01*
X488100Y-2279D01*
X488147Y-2302D01*
X488190Y-2331D01*
X488230Y-2366D01*
X488264Y-2405D01*
X488293Y-2449D01*
X488317Y-2496D01*
X488334Y-2546D01*
X488344Y-2597D01*
X488347Y-2649D01*
Y-2682D01*
Y-2714D01*
Y-2746D01*
Y-2778D01*
Y-2811D01*
Y-2843D01*
Y-2875D01*
Y-2907D01*
Y-2940D01*
Y-2972D01*
Y-3004D01*
Y-3036D01*
Y-3069D01*
Y-3101D01*
Y-3133D01*
Y-3165D01*
Y-3198D01*
Y-3230D01*
Y-3262D01*
Y-3295D01*
Y-3327D01*
Y-3359D01*
Y-3391D01*
Y-3424D01*
Y-3456D01*
Y-3488D01*
Y-3520D01*
Y-3553D01*
Y-3585D01*
Y-3617D01*
Y-3650D01*
Y-3682D01*
Y-3714D01*
Y-3746D01*
Y-3779D01*
Y-3811D01*
Y-3843D01*
Y-3875D01*
Y-3907D01*
Y-3940D01*
Y-3972D01*
Y-4004D01*
Y-4037D01*
Y-4069D01*
Y-4101D01*
Y-4133D01*
Y-4166D01*
Y-4198D01*
Y-4230D01*
Y-4262D01*
Y-4295D01*
Y-4327D01*
Y-4359D01*
X488344Y-4411D01*
X488334Y-4463D01*
X488317Y-4513D01*
X488293Y-4560D01*
X488264Y-4603D01*
X488230Y-4643D01*
X488190Y-4677D01*
X488147Y-4706D01*
X488100Y-4730D01*
X488050Y-4746D01*
X487999Y-4757D01*
X487946Y-4760D01*
X485527D01*
X485474Y-4757D01*
X485423Y-4746D01*
X485373Y-4730D01*
X485326Y-4706D01*
X485283Y-4677D01*
X485243Y-4643D01*
X485209Y-4603D01*
X485180Y-4560D01*
X485156Y-4513D01*
X485139Y-4463D01*
X485129Y-4411D01*
X485126Y-4359D01*
Y-4327D01*
Y-4295D01*
Y-4262D01*
Y-4230D01*
Y-4198D01*
Y-4166D01*
Y-4133D01*
Y-4101D01*
Y-4069D01*
Y-4037D01*
Y-4004D01*
Y-3972D01*
Y-3940D01*
Y-3907D01*
Y-3875D01*
Y-3843D01*
Y-3811D01*
Y-3779D01*
Y-3746D01*
Y-3714D01*
Y-3682D01*
Y-3650D01*
Y-3617D01*
Y-3585D01*
Y-3553D01*
Y-3520D01*
Y-3488D01*
Y-3456D01*
Y-3424D01*
Y-3391D01*
Y-3359D01*
Y-3327D01*
Y-3295D01*
Y-3262D01*
Y-3230D01*
Y-3198D01*
Y-3165D01*
Y-3133D01*
Y-3101D01*
Y-3069D01*
Y-3036D01*
Y-3004D01*
Y-2972D01*
Y-2940D01*
Y-2907D01*
Y-2875D01*
Y-2843D01*
Y-2811D01*
Y-2778D01*
Y-2746D01*
Y-2714D01*
Y-2682D01*
Y-2649D01*
X485129Y-2597D01*
X485139Y-2546D01*
X485156Y-2496D01*
X485180Y-2449D01*
X485209Y-2405D01*
X485243Y-2366D01*
X485283Y-2331D01*
X485326Y-2302D01*
X485373Y-2279D01*
X485423Y-2262D01*
X485474Y-2252D01*
X485527Y-2248D01*
X487946D01*
X487999Y-2252D01*
D02*
G37*
D32*
X267547Y-356432D02*
Y-360430D01*
X268880Y-361763D01*
X270213Y-360430D01*
X271545Y-361763D01*
X272878Y-360430D01*
Y-356432D01*
X275544D02*
Y-360430D01*
X276877Y-361763D01*
X278210Y-360430D01*
X279543Y-361763D01*
X280876Y-360430D01*
Y-356432D01*
X283542D02*
Y-360430D01*
X284875Y-361763D01*
X286207Y-360430D01*
X287540Y-361763D01*
X288873Y-360430D01*
Y-356432D01*
X291539Y-361763D02*
Y-360430D01*
X292872D01*
Y-361763D01*
X291539D01*
X299536Y-355099D02*
Y-356432D01*
X298203D01*
X300869D01*
X299536D01*
Y-360430D01*
X300869Y-361763D01*
X304868D02*
X307534D01*
X306201D01*
Y-356432D01*
X304868D01*
X311532Y-361763D02*
Y-356432D01*
X312865D01*
X314198Y-357765D01*
Y-361763D01*
Y-357765D01*
X315531Y-356432D01*
X316864Y-357765D01*
Y-361763D01*
X319530D02*
X322196D01*
X320863D01*
Y-356432D01*
X319530D01*
X326194Y-361763D02*
Y-356432D01*
X330193D01*
X331526Y-357765D01*
Y-361763D01*
X336858Y-364429D02*
X338191D01*
X339523Y-363096D01*
Y-356432D01*
X335525D01*
X334192Y-357765D01*
Y-360430D01*
X335525Y-361763D01*
X339523D01*
X347521Y-356432D02*
X343522D01*
X342189Y-357765D01*
Y-360430D01*
X343522Y-361763D01*
X347521D01*
X351519Y-356432D02*
X354185D01*
X355518Y-357765D01*
Y-361763D01*
X351519D01*
X350187Y-360430D01*
X351519Y-359098D01*
X355518D01*
X358184Y-356432D02*
Y-361763D01*
Y-359098D01*
X359517Y-357765D01*
X360850Y-356432D01*
X362183D01*
X371513Y-353766D02*
Y-361763D01*
X367514D01*
X366181Y-360430D01*
Y-357765D01*
X367514Y-356432D01*
X371513D01*
X374179Y-361763D02*
Y-360430D01*
X375512D01*
Y-361763D01*
X374179D01*
X386175Y-356432D02*
X382176D01*
X380843Y-357765D01*
Y-360430D01*
X382176Y-361763D01*
X386175D01*
X390174D02*
X392840D01*
X394172Y-360430D01*
Y-357765D01*
X392840Y-356432D01*
X390174D01*
X388841Y-357765D01*
Y-360430D01*
X390174Y-361763D01*
X396838D02*
Y-356432D01*
X398171D01*
X399504Y-357765D01*
Y-361763D01*
Y-357765D01*
X400837Y-356432D01*
X402170Y-357765D01*
Y-361763D01*
D44*
X57422Y-120856D02*
D03*
Y-125581D02*
D03*
D45*
X58210Y-108061D02*
D03*
X64903D02*
D03*
D49*
X436811Y-137992D02*
D03*
Y-144095D02*
D03*
Y-159646D02*
D03*
Y-153543D02*
D03*
X408858Y-137992D02*
D03*
Y-144095D02*
D03*
Y-153543D02*
D03*
Y-159646D02*
D03*
X47441Y-27362D02*
D03*
Y-21260D02*
D03*
Y-5709D02*
D03*
Y-11811D02*
D03*
X75394Y-27362D02*
D03*
Y-21260D02*
D03*
Y-11811D02*
D03*
Y-5709D02*
D03*
D50*
X427559Y-137992D02*
D03*
X422835D02*
D03*
X418110D02*
D03*
Y-159646D02*
D03*
X422835D02*
D03*
X427559D02*
D03*
Y-148819D02*
D03*
X422835D02*
D03*
X418110D02*
D03*
X427559Y-153543D02*
D03*
X422835D02*
D03*
X418110D02*
D03*
X422835Y-144095D02*
D03*
X418110D02*
D03*
X61417Y-21260D02*
D03*
Y-16535D02*
D03*
X56693Y-27362D02*
D03*
X61417D02*
D03*
X66142D02*
D03*
Y-5709D02*
D03*
X61417D02*
D03*
X56693D02*
D03*
Y-16535D02*
D03*
X66142D02*
D03*
X56693Y-11811D02*
D03*
X61417D02*
D03*
X66142D02*
D03*
Y-21260D02*
D03*
D51*
X427409Y-144269D02*
D03*
X56843Y-21085D02*
D03*
D52*
X159390Y-99990D02*
D03*
Y-101565D02*
D03*
Y-103139D02*
D03*
X163445D02*
D03*
Y-101565D02*
D03*
Y-99990D02*
D03*
D53*
X161417Y-101565D02*
D03*
D54*
X109095Y12205D02*
D03*
X85394D02*
D03*
X72480Y12598D02*
D03*
X48779D02*
D03*
X334567Y-133858D02*
D03*
X358268D02*
D03*
X83819Y-77165D02*
D03*
X107520D02*
D03*
D61*
X597835Y-233071D02*
D03*
X603740D02*
D03*
X605905Y-186107D02*
D03*
X600000D02*
D03*
X600591Y-150000D02*
D03*
X594685D02*
D03*
X457480Y-76378D02*
D03*
X451575D02*
D03*
X92323Y-92126D02*
D03*
X98228D02*
D03*
X597835Y-220472D02*
D03*
X603740D02*
D03*
X597835Y-226772D02*
D03*
X603740D02*
D03*
X31693Y-1969D02*
D03*
X25787D02*
D03*
X31693Y4921D02*
D03*
X25787D02*
D03*
X31693Y11811D02*
D03*
X25787D02*
D03*
X31693Y18701D02*
D03*
X25787D02*
D03*
D62*
X595036Y-211353D02*
D03*
Y-206353D02*
D03*
Y-201353D02*
D03*
Y-196353D02*
D03*
X624918D02*
D03*
Y-201353D02*
D03*
Y-206353D02*
D03*
Y-211353D02*
D03*
D65*
X478346Y-303937D02*
D03*
X150787Y394D02*
D03*
D66*
X475394Y-298237D02*
D03*
X477362D02*
D03*
X479331D02*
D03*
X481299D02*
D03*
Y-309637D02*
D03*
X479331D02*
D03*
X477362D02*
D03*
X475394D02*
D03*
X147835Y6094D02*
D03*
X149803D02*
D03*
X151772D02*
D03*
X153740D02*
D03*
Y-5306D02*
D03*
X151772D02*
D03*
X149803D02*
D03*
X147835D02*
D03*
D67*
X484047Y-300984D02*
D03*
Y-302953D02*
D03*
Y-304921D02*
D03*
Y-306890D02*
D03*
X472647D02*
D03*
Y-304921D02*
D03*
Y-302953D02*
D03*
Y-300984D02*
D03*
X156487Y3347D02*
D03*
Y1378D02*
D03*
Y-591D02*
D03*
Y-2559D02*
D03*
X145087D02*
D03*
Y-591D02*
D03*
Y1378D02*
D03*
Y3347D02*
D03*
D70*
X203839Y-56693D02*
D03*
X174114Y-2559D02*
D03*
X203839Y-3543D02*
D03*
X174114Y-4528D02*
D03*
X203839Y-5512D02*
D03*
X174114Y-6496D02*
D03*
X203839Y-7480D02*
D03*
X174114Y-8465D02*
D03*
X203839Y-9449D02*
D03*
X174114Y-10433D02*
D03*
X203839Y-11417D02*
D03*
X174114Y-12402D02*
D03*
X203839Y-13386D02*
D03*
X174114Y-14370D02*
D03*
X203839Y-15354D02*
D03*
X174114Y-16339D02*
D03*
X203839Y-17323D02*
D03*
X174114Y-18307D02*
D03*
X203839Y-19291D02*
D03*
X174114Y-20276D02*
D03*
X203839Y-21260D02*
D03*
X174114Y-22244D02*
D03*
X203839Y-23228D02*
D03*
X174114Y-24213D02*
D03*
X203839Y-25197D02*
D03*
X174114Y-26181D02*
D03*
X203839Y-27165D02*
D03*
X174114Y-28150D02*
D03*
X203839Y-29134D02*
D03*
X174114Y-30118D02*
D03*
X203839Y-31102D02*
D03*
X174114Y-32087D02*
D03*
X203839Y-33071D02*
D03*
X174114Y-34055D02*
D03*
X203839Y-35039D02*
D03*
X174114Y-36024D02*
D03*
X203839Y-37008D02*
D03*
X174114Y-37992D02*
D03*
X203839Y-38976D02*
D03*
X174114Y-39961D02*
D03*
X203839Y-40945D02*
D03*
X174114Y-41929D02*
D03*
X203839Y-42913D02*
D03*
X174114Y-43898D02*
D03*
X203839Y-44882D02*
D03*
X174114Y-45866D02*
D03*
X203839Y-46850D02*
D03*
X174114Y-47835D02*
D03*
X203839Y-48819D02*
D03*
X174114Y-49803D02*
D03*
X203839Y-50787D02*
D03*
X174114Y-51772D02*
D03*
X203839Y-52756D02*
D03*
X174114Y-53740D02*
D03*
X203839Y-54724D02*
D03*
X174114Y-55709D02*
D03*
X203839Y-66535D02*
D03*
Y-68504D02*
D03*
Y-70472D02*
D03*
Y-72441D02*
D03*
Y-74410D02*
D03*
X174114Y-65551D02*
D03*
Y-67520D02*
D03*
Y-69488D02*
D03*
Y-71457D02*
D03*
Y-73425D02*
D03*
Y-75394D02*
D03*
D71*
X177165Y1772D02*
D03*
Y-79724D02*
D03*
D72*
X553543Y-262402D02*
D03*
X499409Y-292126D02*
D03*
X500394Y-262402D02*
D03*
X501378Y-292126D02*
D03*
X502362Y-262402D02*
D03*
X503346Y-292126D02*
D03*
X504331Y-262402D02*
D03*
X505315Y-292126D02*
D03*
X506299Y-262402D02*
D03*
X507283Y-292126D02*
D03*
X508268Y-262402D02*
D03*
X509252Y-292126D02*
D03*
X510236Y-262402D02*
D03*
X511221Y-292126D02*
D03*
X512205Y-262402D02*
D03*
X513189Y-292126D02*
D03*
X514173Y-262402D02*
D03*
X515158Y-292126D02*
D03*
X516142Y-262402D02*
D03*
X517126Y-292126D02*
D03*
X518110Y-262402D02*
D03*
X519095Y-292126D02*
D03*
X520079Y-262402D02*
D03*
X521063Y-292126D02*
D03*
X522047Y-262402D02*
D03*
X523032Y-292126D02*
D03*
X524016Y-262402D02*
D03*
X525000Y-292126D02*
D03*
X525984Y-262402D02*
D03*
X526968Y-292126D02*
D03*
X527953Y-262402D02*
D03*
X528937Y-292126D02*
D03*
X529921Y-262402D02*
D03*
X530905Y-292126D02*
D03*
X531890Y-262402D02*
D03*
X532874Y-292126D02*
D03*
X533858Y-262402D02*
D03*
X534842Y-292126D02*
D03*
X535827Y-262402D02*
D03*
X536811Y-292126D02*
D03*
X537795Y-262402D02*
D03*
X538779Y-292126D02*
D03*
X539764Y-262402D02*
D03*
X540748Y-292126D02*
D03*
X541732Y-262402D02*
D03*
X542717Y-292126D02*
D03*
X543701Y-262402D02*
D03*
X544685Y-292126D02*
D03*
X545669Y-262402D02*
D03*
X546654Y-292126D02*
D03*
X547638Y-262402D02*
D03*
X548622Y-292126D02*
D03*
X549606Y-262402D02*
D03*
X550591Y-292126D02*
D03*
X551575Y-262402D02*
D03*
X552559Y-292126D02*
D03*
X563386Y-262402D02*
D03*
X565354D02*
D03*
X567323D02*
D03*
X569291D02*
D03*
X571260D02*
D03*
X562402Y-292126D02*
D03*
X564370D02*
D03*
X566339D02*
D03*
X568307D02*
D03*
X570276D02*
D03*
X572244D02*
D03*
D73*
X495079Y-289075D02*
D03*
X576575D02*
D03*
D74*
X545448Y-27614D02*
D03*
Y-45614D02*
D03*
D75*
X572698Y-36614D02*
D03*
D78*
X105282Y-19291D02*
D03*
D79*
X97408D02*
D03*
D80*
Y-10197D02*
D03*
D81*
X103943D02*
D03*
D82*
X107132D02*
D03*
D83*
X110958Y-7480D02*
D03*
Y-10630D02*
D03*
Y-13780D02*
D03*
Y-16929D02*
D03*
Y-20079D02*
D03*
X90158D02*
D03*
Y-16929D02*
D03*
Y-13780D02*
D03*
Y-10630D02*
D03*
Y-7480D02*
D03*
X411647Y-122343D02*
D03*
Y-119193D02*
D03*
Y-116043D02*
D03*
Y-112894D02*
D03*
Y-109744D02*
D03*
X432447D02*
D03*
Y-112894D02*
D03*
Y-116043D02*
D03*
Y-119193D02*
D03*
Y-122343D02*
D03*
D84*
X106857Y-24180D02*
D03*
X103707D02*
D03*
X100557D02*
D03*
X97408D02*
D03*
X94258D02*
D03*
Y-3379D02*
D03*
X97408D02*
D03*
X100557D02*
D03*
X103707D02*
D03*
X106857D02*
D03*
X428346Y-126443D02*
D03*
X425197D02*
D03*
X422047D02*
D03*
X418898D02*
D03*
X415748D02*
D03*
Y-105643D02*
D03*
X418898D02*
D03*
X422047D02*
D03*
X425197D02*
D03*
X428346D02*
D03*
D85*
X453937Y-136181D02*
D03*
Y-159882D02*
D03*
X457480Y-90118D02*
D03*
Y-113819D02*
D03*
D86*
X356750Y-119882D02*
D03*
X352982D02*
D03*
D87*
X390654Y-113429D02*
D03*
Y-110551D02*
D03*
X14173Y-299864D02*
D03*
Y-296986D02*
D03*
D88*
X353029Y-113189D02*
D03*
X356703D02*
D03*
D89*
X383268Y-114567D02*
D03*
Y-109055D02*
D03*
X148425Y-104336D02*
D03*
Y-98824D02*
D03*
D90*
X428300Y-192653D02*
D03*
X424560Y-201048D02*
D03*
X432040D02*
D03*
X424560Y-192653D02*
D03*
D91*
X432040D02*
D03*
D92*
X373083Y-155512D02*
D03*
X378083D02*
D03*
X388083Y-134252D02*
D03*
X383083D02*
D03*
X378083D02*
D03*
X373083D02*
D03*
X383083Y-155512D02*
D03*
X388083D02*
D03*
X613406Y-83465D02*
D03*
X608405D02*
D03*
X598406Y-62205D02*
D03*
X603406D02*
D03*
X608405D02*
D03*
X613406D02*
D03*
X603406Y-83465D02*
D03*
X598406D02*
D03*
D94*
X66102Y-43355D02*
D03*
X44842Y-58355D02*
D03*
Y-53355D02*
D03*
X66102Y-48355D02*
D03*
Y-53355D02*
D03*
Y-58355D02*
D03*
X44842Y-48355D02*
D03*
Y-43355D02*
D03*
D95*
X25686Y-18898D02*
D03*
X35731D02*
D03*
X464961Y-125197D02*
D03*
X454915D02*
D03*
X25686Y-9843D02*
D03*
X35731D02*
D03*
D96*
X416535Y-120768D02*
D03*
D97*
Y-112894D02*
D03*
D98*
X425630D02*
D03*
D99*
Y-119429D02*
D03*
D100*
Y-122618D02*
D03*
D101*
X443307Y-112300D02*
D03*
Y-122346D02*
D03*
D102*
X362402Y-111811D02*
D03*
X375394D02*
D03*
X74616Y-61723D02*
D03*
X87608D02*
D03*
D103*
X334646Y-153937D02*
D03*
X358268D02*
D03*
D104*
X103543Y-61811D02*
D03*
Y-38189D02*
D03*
D105*
X93299Y-99606D02*
D03*
X97253D02*
D03*
X471662Y-76378D02*
D03*
X467708D02*
D03*
D111*
X182516Y-128347D02*
D03*
Y-118504D02*
D03*
D113*
X168110Y-100132D02*
D03*
Y-103805D02*
D03*
D120*
X8403Y-237795D02*
D03*
X11282D02*
D03*
X5647Y-349213D02*
D03*
X8526D02*
D03*
X10372Y-193307D02*
D03*
X13250D02*
D03*
X616006Y-302756D02*
D03*
X613128D02*
D03*
D124*
X153150Y-103459D02*
D03*
Y-99691D02*
D03*
D125*
X127981Y-132385D02*
D03*
X130540D02*
D03*
X127981Y-124314D02*
D03*
X130540D02*
D03*
X133099D02*
D03*
X135658D02*
D03*
Y-132385D02*
D03*
X133099D02*
D03*
D128*
X612648Y-256693D02*
D03*
X608612D02*
D03*
D129*
X610827Y-235433D02*
D03*
X612598D02*
D03*
X614370D02*
D03*
X616142D02*
D03*
X617913D02*
D03*
X619685D02*
D03*
Y-246579D02*
D03*
X617913D02*
D03*
X616142D02*
D03*
X614370D02*
D03*
X612598D02*
D03*
D130*
X610827D02*
D03*
D131*
X605418Y-300000D02*
D03*
X599307D02*
D03*
D132*
X596063Y-292126D02*
D03*
X600000D02*
D03*
X608661Y-261024D02*
D03*
X612598D02*
D03*
D133*
X550787Y-64567D02*
D03*
X576772D02*
D03*
D145*
X166178Y-135679D02*
D03*
X160272D02*
D03*
Y-117471D02*
D03*
X166178D02*
D03*
D146*
X164209Y-135679D02*
D03*
X162241D02*
D03*
X162241Y-117471D02*
D03*
X164209D02*
D03*
D147*
X169377Y-135433D02*
D03*
X169376Y-131496D02*
D03*
X169377Y-127559D02*
D03*
Y-125590D02*
D03*
X169376Y-121654D02*
D03*
X169377Y-117716D02*
D03*
X157073Y-135433D02*
D03*
X157073Y-131496D02*
D03*
X157073Y-127559D02*
D03*
Y-125591D02*
D03*
X157073Y-121653D02*
D03*
X157073Y-117717D02*
D03*
D148*
X169377Y-133465D02*
D03*
Y-129528D02*
D03*
Y-123622D02*
D03*
Y-119685D02*
D03*
X157073Y-133465D02*
D03*
Y-129528D02*
D03*
Y-123622D02*
D03*
Y-119685D02*
D03*
D149*
X118504Y-390698D02*
D03*
D150*
X216142Y-404084D02*
D03*
D151*
X84981Y-123809D02*
D03*
D152*
X79076Y-114655D02*
D03*
X81044D02*
D03*
X83013D02*
D03*
X84981D02*
D03*
X86950D02*
D03*
X88918D02*
D03*
X90887D02*
D03*
X90887Y-132963D02*
D03*
X88918D02*
D03*
X86950D02*
D03*
X84981D02*
D03*
X83013D02*
D03*
X81044D02*
D03*
X79076D02*
D03*
D153*
X94135Y-117904D02*
D03*
Y-119872D02*
D03*
Y-121841D02*
D03*
Y-123809D02*
D03*
Y-125778D02*
D03*
Y-127746D02*
D03*
Y-129715D02*
D03*
X75828Y-125778D02*
D03*
Y-123809D02*
D03*
Y-121841D02*
D03*
Y-119872D02*
D03*
Y-117904D02*
D03*
Y-127746D02*
D03*
Y-129715D02*
D03*
D154*
X58407Y-133652D02*
D03*
X64312D02*
D03*
D155*
X47777Y-115541D02*
D03*
X50926D02*
D03*
X50926Y-111604D02*
D03*
X47777D02*
D03*
X50926Y-108061D02*
D03*
X47777D02*
D03*
X160236Y-54331D02*
D03*
X163386D02*
D03*
X544882Y-300787D02*
D03*
X541732D02*
D03*
X160236Y-59055D02*
D03*
X163386D02*
D03*
X548819Y-300787D02*
D03*
X551968D02*
D03*
X181335Y-132874D02*
D03*
X184485D02*
D03*
X181335Y-113583D02*
D03*
X184485D02*
D03*
D156*
X63918Y-121053D02*
D03*
Y-126565D02*
D03*
X253082Y-115065D02*
D03*
Y-120577D02*
D03*
X611811Y-38189D02*
D03*
Y-43701D02*
D03*
D157*
X128523Y-116147D02*
D03*
X134034D02*
D03*
X128459Y-110462D02*
D03*
X133971D02*
D03*
D158*
X262456Y-120276D02*
D03*
Y-113189D02*
D03*
X620866Y-35827D02*
D03*
Y-42913D02*
D03*
D159*
X264469Y-128937D02*
D03*
X276083D02*
D03*
Y-141142D02*
D03*
X264469D02*
D03*
X276083Y-152559D02*
D03*
X264469D02*
D03*
D160*
X382776Y-241437D02*
D03*
X385335D02*
D03*
X387894D02*
D03*
X390453D02*
D03*
Y-227067D02*
D03*
X387894D02*
D03*
X385335D02*
D03*
X382776D02*
D03*
D161*
X393799Y-238090D02*
D03*
Y-235531D02*
D03*
Y-232972D02*
D03*
Y-230413D02*
D03*
X379429D02*
D03*
Y-232972D02*
D03*
Y-235531D02*
D03*
Y-238090D02*
D03*
D162*
X386614Y-234252D02*
D03*
D163*
X609547Y-277461D02*
D03*
Y-280020D02*
D03*
Y-274902D02*
D03*
Y-282579D02*
D03*
Y-285138D02*
D03*
D164*
X620079Y-284547D02*
D03*
Y-275492D02*
D03*
D165*
X147047Y-26033D02*
D03*
Y-33907D02*
D03*
Y-41781D02*
D03*
Y-49655D02*
D03*
X129547Y-26033D02*
D03*
Y-33907D02*
D03*
Y-41781D02*
D03*
Y-18159D02*
D03*
Y-73277D02*
D03*
Y-57529D02*
D03*
Y-65403D02*
D03*
Y-49655D02*
D03*
X147047Y-73277D02*
D03*
Y-65403D02*
D03*
Y-57529D02*
D03*
Y-18159D02*
D03*
Y-49655D02*
D03*
Y-57529D02*
D03*
Y-65403D02*
D03*
Y-73277D02*
D03*
X129547Y-49655D02*
D03*
Y-65403D02*
D03*
Y-57529D02*
D03*
Y-73277D02*
D03*
D166*
X133957Y-9843D02*
D03*
X136909D02*
D03*
X489862Y-314173D02*
D03*
X492815D02*
D03*
X177657Y-87795D02*
D03*
X180610D02*
D03*
X178051Y-101181D02*
D03*
X181004D02*
D03*
X201476Y-87795D02*
D03*
X198524D02*
D03*
X200295Y-102756D02*
D03*
X197343D02*
D03*
X180610Y-92126D02*
D03*
X177657D02*
D03*
X198524Y-91732D02*
D03*
X201476D02*
D03*
X609547Y-252756D02*
D03*
X612500D02*
D03*
X294783Y-194095D02*
D03*
X291831D02*
D03*
X292815Y-189764D02*
D03*
X289862D02*
D03*
X269783Y-192126D02*
D03*
X272736D02*
D03*
X269783Y-196457D02*
D03*
X272736D02*
D03*
D167*
X590530Y-163898D02*
D03*
Y-173898D02*
D03*
X624430Y-163898D02*
D03*
Y-173898D02*
D03*
D168*
X599016Y-144488D02*
D03*
X595472D02*
D03*
X492323Y-303543D02*
D03*
X495866D02*
D03*
X484842Y-317717D02*
D03*
X488386D02*
D03*
X489567Y-310236D02*
D03*
X493110D02*
D03*
X473819Y-315354D02*
D03*
X470276D02*
D03*
X144685Y-11811D02*
D03*
X141142D02*
D03*
X137598Y-6299D02*
D03*
X134055D02*
D03*
X312402Y-243307D02*
D03*
X315945D02*
D03*
X370669Y-236614D02*
D03*
X374213D02*
D03*
X370669Y-241339D02*
D03*
X374213D02*
D03*
X396654Y-219291D02*
D03*
X393110D02*
D03*
X337992Y-235827D02*
D03*
X334449D02*
D03*
X320669Y-250787D02*
D03*
X324213D02*
D03*
X320669Y-228740D02*
D03*
X324213D02*
D03*
X338386Y-242913D02*
D03*
X334842D02*
D03*
X315158Y-236221D02*
D03*
X318701D02*
D03*
X337598Y-281102D02*
D03*
X341142D02*
D03*
X337992Y-303150D02*
D03*
X341535D02*
D03*
X318307Y-283465D02*
D03*
X321850D02*
D03*
X317913Y-303543D02*
D03*
X321457D02*
D03*
X600689Y-238976D02*
D03*
X604232D02*
D03*
X352362Y-288583D02*
D03*
X348819D02*
D03*
X351575Y-296063D02*
D03*
X348031D02*
D03*
X308071Y-289370D02*
D03*
X311614D02*
D03*
X307283Y-296457D02*
D03*
X310827D02*
D03*
X600689Y-242913D02*
D03*
X604232D02*
D03*
X613976Y-228740D02*
D03*
X610433D02*
D03*
X620669Y-228346D02*
D03*
X624213D02*
D03*
D169*
X482874Y-262598D02*
D03*
Y-264173D02*
D03*
Y-265748D02*
D03*
Y-267323D02*
D03*
Y-268898D02*
D03*
X477756D02*
D03*
Y-267323D02*
D03*
Y-265748D02*
D03*
Y-264173D02*
D03*
X328150Y-236614D02*
D03*
Y-238189D02*
D03*
Y-239764D02*
D03*
Y-241339D02*
D03*
Y-242913D02*
D03*
X323031D02*
D03*
Y-241339D02*
D03*
Y-239764D02*
D03*
Y-238189D02*
D03*
X341929Y-289764D02*
D03*
Y-291339D02*
D03*
Y-292913D02*
D03*
Y-294488D02*
D03*
Y-296063D02*
D03*
X336811D02*
D03*
Y-294488D02*
D03*
Y-292913D02*
D03*
Y-291339D02*
D03*
X323031Y-290551D02*
D03*
Y-292126D02*
D03*
Y-293701D02*
D03*
Y-295276D02*
D03*
Y-296850D02*
D03*
X317913D02*
D03*
Y-295276D02*
D03*
Y-293701D02*
D03*
Y-292126D02*
D03*
D170*
X480315Y-268898D02*
D03*
Y-262598D02*
D03*
X325590Y-242913D02*
D03*
Y-236614D02*
D03*
X339370Y-296063D02*
D03*
Y-289764D02*
D03*
X320472Y-296850D02*
D03*
Y-290551D02*
D03*
D171*
X478543Y-262598D02*
D03*
X186614Y-96260D02*
D03*
X278740Y-197047D02*
D03*
X323819Y-236614D02*
D03*
X337598Y-289764D02*
D03*
X318701Y-290551D02*
D03*
D172*
X482677Y-276476D02*
D03*
Y-279429D02*
D03*
X483071Y-256988D02*
D03*
Y-254035D02*
D03*
X479921Y-279429D02*
D03*
Y-276476D02*
D03*
X485827Y-279429D02*
D03*
Y-276476D02*
D03*
X476772Y-254035D02*
D03*
Y-256988D02*
D03*
X487402Y-254035D02*
D03*
Y-256988D02*
D03*
X465748Y-308760D02*
D03*
Y-311713D02*
D03*
X488583Y-295177D02*
D03*
Y-292224D02*
D03*
X472835Y-292028D02*
D03*
Y-289075D02*
D03*
X146850Y14272D02*
D03*
Y17224D02*
D03*
X164567Y9941D02*
D03*
Y12894D02*
D03*
X158661Y-9941D02*
D03*
Y-12894D02*
D03*
X283858Y-204232D02*
D03*
Y-207185D02*
D03*
X285827Y-186909D02*
D03*
Y-183957D02*
D03*
X279528Y-204429D02*
D03*
Y-207382D02*
D03*
X278346Y-186909D02*
D03*
Y-183957D02*
D03*
D173*
X461417Y-308465D02*
D03*
Y-312008D02*
D03*
X476772Y-291929D02*
D03*
Y-288386D02*
D03*
X483465Y-291535D02*
D03*
Y-287992D02*
D03*
X466142Y-298228D02*
D03*
Y-294685D02*
D03*
X142520Y13189D02*
D03*
Y16732D02*
D03*
X162598Y-9646D02*
D03*
Y-13189D02*
D03*
X159843Y9646D02*
D03*
Y13189D02*
D03*
X151181Y14370D02*
D03*
Y17913D02*
D03*
X153543Y-10433D02*
D03*
Y-13976D02*
D03*
X169291Y9646D02*
D03*
Y13189D02*
D03*
X382677Y-249803D02*
D03*
Y-246260D02*
D03*
X333071Y-282480D02*
D03*
Y-286024D02*
D03*
Y-302559D02*
D03*
Y-299016D02*
D03*
X327953Y-282480D02*
D03*
Y-286024D02*
D03*
X328740Y-302362D02*
D03*
Y-298819D02*
D03*
D174*
X186614Y-91929D02*
D03*
X188189D02*
D03*
X189764D02*
D03*
X191339D02*
D03*
X192913D02*
D03*
Y-97047D02*
D03*
X191339D02*
D03*
X189764D02*
D03*
X188189D02*
D03*
X280315Y-197835D02*
D03*
X281890D02*
D03*
X283465D02*
D03*
X285039D02*
D03*
Y-192717D02*
D03*
X283465D02*
D03*
X281890D02*
D03*
X280315D02*
D03*
X278740D02*
D03*
D175*
X192913Y-94488D02*
D03*
X186614D02*
D03*
X278740Y-195276D02*
D03*
X285039D02*
D03*
D176*
X399410Y-120866D02*
D03*
X388976D02*
D03*
X77067Y-40157D02*
D03*
X87500D02*
D03*
X589764Y-52362D02*
D03*
X600197D02*
D03*
D177*
X386319Y-217717D02*
D03*
X382972D02*
D03*
X131004Y-348031D02*
D03*
X134350D02*
D03*
X131004Y-352362D02*
D03*
X134350D02*
D03*
X18799Y-350000D02*
D03*
X22146D02*
D03*
X3445Y-234646D02*
D03*
X6791D02*
D03*
X23524Y-239370D02*
D03*
X26870D02*
D03*
X23130Y-192520D02*
D03*
X26476D02*
D03*
X405807Y-233071D02*
D03*
X409154D02*
D03*
X405413Y-238189D02*
D03*
X408760D02*
D03*
X404626Y-219685D02*
D03*
X407972D02*
D03*
X404626Y-224016D02*
D03*
X407972D02*
D03*
X374902Y-217717D02*
D03*
X371555D02*
D03*
D178*
X387509Y-173797D02*
D03*
X334360Y-189741D02*
D03*
X387509D02*
D03*
X389478D02*
D03*
Y-173797D02*
D03*
X379635D02*
D03*
X369793D02*
D03*
X359950D02*
D03*
X350108D02*
D03*
X340265D02*
D03*
X330423D02*
D03*
X320580D02*
D03*
X379635Y-189741D02*
D03*
X369793D02*
D03*
X359950D02*
D03*
X350108D02*
D03*
X340265D02*
D03*
X330423D02*
D03*
X320580D02*
D03*
X385541D02*
D03*
Y-173797D02*
D03*
X332391Y-189741D02*
D03*
X352076Y-173797D02*
D03*
X328454Y-189741D02*
D03*
X312706Y-173797D02*
D03*
X322549Y-189741D02*
D03*
X312706D02*
D03*
X318612D02*
D03*
X357982Y-173797D02*
D03*
X344202D02*
D03*
X314675D02*
D03*
X316643Y-189741D02*
D03*
X356013Y-173797D02*
D03*
X322549D02*
D03*
X328454D02*
D03*
X318612D02*
D03*
X354045D02*
D03*
X342234D02*
D03*
X334360D02*
D03*
X324517D02*
D03*
X314675Y-189741D02*
D03*
X316643Y-173797D02*
D03*
X324517Y-189741D02*
D03*
X363887Y-173797D02*
D03*
X361919D02*
D03*
X326486D02*
D03*
X332391D02*
D03*
X338297Y-189741D02*
D03*
X336328D02*
D03*
X375698Y-173797D02*
D03*
X352076Y-189741D02*
D03*
X356013D02*
D03*
X381604Y-173797D02*
D03*
X346171Y-189741D02*
D03*
X361919D02*
D03*
X365856D02*
D03*
X373730D02*
D03*
X377667Y-173797D02*
D03*
X367824D02*
D03*
X348139Y-189741D02*
D03*
X326486D02*
D03*
X381604D02*
D03*
X383572Y-173797D02*
D03*
X371761D02*
D03*
X365856D02*
D03*
X373730D02*
D03*
X357982Y-189741D02*
D03*
X354045D02*
D03*
X375698D02*
D03*
X363887D02*
D03*
X383572D02*
D03*
X367824D02*
D03*
X342234D02*
D03*
X344202D02*
D03*
X338297Y-173797D02*
D03*
X336328D02*
D03*
X348139D02*
D03*
X346171D02*
D03*
X371761Y-189741D02*
D03*
X377667D02*
D03*
X357972Y-321918D02*
D03*
X359940D02*
D03*
X334350D02*
D03*
X318602D02*
D03*
X330413D02*
D03*
X338287D02*
D03*
X326476D02*
D03*
X348129D02*
D03*
X344192D02*
D03*
X328444Y-337862D02*
D03*
X336318D02*
D03*
X330413D02*
D03*
X318602D02*
D03*
X320570Y-321918D02*
D03*
X324507D02*
D03*
X375688D02*
D03*
X354035D02*
D03*
X334350Y-337862D02*
D03*
X324507D02*
D03*
X328444Y-321918D02*
D03*
X336318D02*
D03*
X340255D02*
D03*
X356003D02*
D03*
X320570Y-337862D02*
D03*
X346161Y-321918D02*
D03*
X350098D02*
D03*
X326476Y-337862D02*
D03*
X365846Y-321918D02*
D03*
X363877D02*
D03*
X369783Y-337862D02*
D03*
X375688D02*
D03*
X340255D02*
D03*
X338287D02*
D03*
X377657Y-321918D02*
D03*
X385531Y-337862D02*
D03*
X387499Y-321918D02*
D03*
X363877Y-337862D02*
D03*
X377657D02*
D03*
X367814D02*
D03*
X365846D02*
D03*
X359940D02*
D03*
X348129D02*
D03*
X354035D02*
D03*
X383562D02*
D03*
X373720D02*
D03*
X379625D02*
D03*
X346161D02*
D03*
X385531Y-321918D02*
D03*
X387499Y-337862D02*
D03*
X357972D02*
D03*
X344192D02*
D03*
X383562Y-321918D02*
D03*
X389468D02*
D03*
X379625D02*
D03*
X389468Y-337862D02*
D03*
X373720Y-321918D02*
D03*
X350098Y-337862D02*
D03*
X356003D02*
D03*
X369783Y-321918D02*
D03*
X316633Y-337862D02*
D03*
Y-321918D02*
D03*
X381594D02*
D03*
X371751D02*
D03*
X361909D02*
D03*
X352066D02*
D03*
X342224D02*
D03*
X332381D02*
D03*
X322539D02*
D03*
X381594Y-337862D02*
D03*
X371751D02*
D03*
X361909D02*
D03*
X352066D02*
D03*
X342224D02*
D03*
X332381D02*
D03*
X322539D02*
D03*
X312696D02*
D03*
Y-321918D02*
D03*
X314665D02*
D03*
X367814D02*
D03*
X314665Y-337862D02*
D03*
D179*
X395083Y-181814D02*
D03*
X307091D02*
D03*
X395083Y-329845D02*
D03*
X307091D02*
D03*
D180*
X238209Y-113386D02*
D03*
X233209D02*
D03*
X228209D02*
D03*
X223209D02*
D03*
X238209Y-132283D02*
D03*
X233209D02*
D03*
X228209D02*
D03*
X223209D02*
D03*
D181*
X214193Y-112795D02*
D03*
X209193D02*
D03*
X204193D02*
D03*
X199193D02*
D03*
X214193Y-131299D02*
D03*
X209193D02*
D03*
X204193D02*
D03*
X199193D02*
D03*
D182*
X189209Y-127323D02*
D03*
Y-131339D02*
D03*
Y-117480D02*
D03*
Y-121496D02*
D03*
D183*
X560778Y-328917D02*
D03*
X545030D02*
D03*
X552904D02*
D03*
X537156D02*
D03*
X560778Y-311417D02*
D03*
X552904D02*
D03*
X545030D02*
D03*
X537156D02*
D03*
X513534D02*
D03*
X521408D02*
D03*
X529282D02*
D03*
X537156D02*
D03*
X513534Y-328917D02*
D03*
X521408D02*
D03*
X529282D02*
D03*
X505660D02*
D03*
X560778D02*
D03*
X545030D02*
D03*
X552904D02*
D03*
X537156D02*
D03*
X560778Y-311417D02*
D03*
X552904D02*
D03*
X545030D02*
D03*
X505660D02*
D03*
D184*
X428390Y-355832D02*
D03*
X419531Y-358391D02*
D03*
Y-353273D02*
D03*
X473173Y-356620D02*
D03*
X464315Y-359179D02*
D03*
Y-354061D02*
D03*
X511594Y-356296D02*
D03*
X502736Y-358855D02*
D03*
Y-353737D02*
D03*
X556575Y-356099D02*
D03*
X547717Y-358659D02*
D03*
Y-353540D02*
D03*
D185*
X481441Y-356620D02*
D03*
X489315D02*
D03*
X436953Y-355832D02*
D03*
X444827D02*
D03*
X521339Y-356296D02*
D03*
X529213D02*
D03*
X565827Y-356690D02*
D03*
X573701D02*
D03*
D186*
X13973Y-210630D02*
D03*
Y-262795D02*
D03*
X13973Y-157332D02*
D03*
X13973Y-316929D02*
D03*
D187*
X19976Y-216437D02*
D03*
Y-204823D02*
D03*
Y-256988D02*
D03*
Y-268602D02*
D03*
X19976Y-151525D02*
D03*
Y-163139D02*
D03*
X19976Y-311122D02*
D03*
Y-322736D02*
D03*
D188*
X-1181Y-349311D02*
D03*
Y-345965D02*
D03*
X390945Y-249114D02*
D03*
Y-252461D02*
D03*
X386614Y-249114D02*
D03*
Y-252461D02*
D03*
X401575Y-249114D02*
D03*
Y-252461D02*
D03*
X396850Y-249114D02*
D03*
Y-252461D02*
D03*
D189*
X-4724Y-178543D02*
D03*
X2756D02*
D03*
Y-187205D02*
D03*
X2756Y-291732D02*
D03*
Y-283071D02*
D03*
X-4724D02*
D03*
D190*
X-3937Y-187205D02*
D03*
X-3937Y-291732D02*
D03*
D191*
X622047Y-343307D02*
D03*
Y-333307D02*
D03*
Y-323307D02*
D03*
Y-313307D02*
D03*
Y-353307D02*
D03*
X602559D02*
D03*
Y-343307D02*
D03*
Y-333307D02*
D03*
Y-323307D02*
D03*
Y-313307D02*
D03*
D192*
X-18406Y-176772D02*
D03*
Y-187795D02*
D03*
Y-59646D02*
D03*
Y-70669D02*
D03*
Y-240551D02*
D03*
Y-229528D02*
D03*
Y-294094D02*
D03*
Y-283071D02*
D03*
Y-346850D02*
D03*
Y-335827D02*
D03*
Y-113976D02*
D03*
Y-102953D02*
D03*
D193*
X-19685Y-180512D02*
D03*
Y-184055D02*
D03*
Y-63386D02*
D03*
Y-66929D02*
D03*
Y-236811D02*
D03*
Y-233268D02*
D03*
Y-290354D02*
D03*
Y-286811D02*
D03*
Y-343110D02*
D03*
Y-339567D02*
D03*
Y-110236D02*
D03*
Y-106693D02*
D03*
D194*
X615256Y-241006D02*
D03*
D195*
X261126Y-299333D02*
D03*
Y-211341D02*
D03*
X448528D02*
D03*
Y-299333D02*
D03*
D196*
X269054Y-262222D02*
D03*
Y-264190D02*
D03*
Y-238600D02*
D03*
Y-222852D02*
D03*
Y-234663D02*
D03*
Y-242537D02*
D03*
Y-230726D02*
D03*
Y-252379D02*
D03*
Y-248442D02*
D03*
X253110Y-232694D02*
D03*
Y-240568D02*
D03*
Y-234663D02*
D03*
Y-222852D02*
D03*
X269054Y-224820D02*
D03*
Y-228757D02*
D03*
Y-279938D02*
D03*
Y-258285D02*
D03*
X253110Y-238600D02*
D03*
Y-228757D02*
D03*
X269054Y-232694D02*
D03*
Y-240568D02*
D03*
Y-244505D02*
D03*
Y-260253D02*
D03*
X253110Y-224820D02*
D03*
X269054Y-250411D02*
D03*
Y-254348D02*
D03*
X253110Y-230726D02*
D03*
X269054Y-270096D02*
D03*
Y-268127D02*
D03*
X253110Y-274033D02*
D03*
Y-279938D02*
D03*
Y-244505D02*
D03*
Y-242537D02*
D03*
X269054Y-281907D02*
D03*
X253110Y-289781D02*
D03*
X269054Y-291749D02*
D03*
X253110Y-268127D02*
D03*
Y-281907D02*
D03*
Y-272064D02*
D03*
Y-270096D02*
D03*
Y-264190D02*
D03*
Y-252379D02*
D03*
Y-258285D02*
D03*
Y-287812D02*
D03*
Y-277970D02*
D03*
Y-283875D02*
D03*
Y-250411D02*
D03*
X269054Y-289781D02*
D03*
X253110Y-291749D02*
D03*
Y-262222D02*
D03*
Y-248442D02*
D03*
X269054Y-287812D02*
D03*
Y-293718D02*
D03*
Y-283875D02*
D03*
X253110Y-293718D02*
D03*
X269054Y-277970D02*
D03*
X253110Y-254348D02*
D03*
Y-260253D02*
D03*
X269054Y-274033D02*
D03*
X253110Y-220883D02*
D03*
X269054D02*
D03*
Y-285844D02*
D03*
Y-276001D02*
D03*
Y-266159D02*
D03*
Y-256316D02*
D03*
Y-246474D02*
D03*
Y-236631D02*
D03*
Y-226789D02*
D03*
X253110Y-285844D02*
D03*
Y-276001D02*
D03*
Y-266159D02*
D03*
Y-256316D02*
D03*
Y-246474D02*
D03*
Y-236631D02*
D03*
Y-226789D02*
D03*
Y-216946D02*
D03*
X269054D02*
D03*
Y-218915D02*
D03*
Y-272064D02*
D03*
X253110Y-218915D02*
D03*
X440601Y-248452D02*
D03*
Y-246484D02*
D03*
Y-272074D02*
D03*
Y-287822D02*
D03*
Y-276011D02*
D03*
Y-268137D02*
D03*
Y-279948D02*
D03*
Y-258295D02*
D03*
Y-262232D02*
D03*
X456545Y-277980D02*
D03*
Y-270106D02*
D03*
Y-276011D02*
D03*
Y-287822D02*
D03*
X440601Y-285854D02*
D03*
Y-281917D02*
D03*
Y-230736D02*
D03*
Y-252389D02*
D03*
X456545Y-272074D02*
D03*
Y-281917D02*
D03*
X440601Y-277980D02*
D03*
Y-270106D02*
D03*
Y-266169D02*
D03*
Y-250421D02*
D03*
X456545Y-285854D02*
D03*
X440601Y-260263D02*
D03*
Y-256326D02*
D03*
X456545Y-279948D02*
D03*
X440601Y-240578D02*
D03*
Y-242547D02*
D03*
X456545Y-236641D02*
D03*
Y-230736D02*
D03*
Y-266169D02*
D03*
Y-268137D02*
D03*
X440601Y-228767D02*
D03*
X456545Y-220893D02*
D03*
X440601Y-218925D02*
D03*
X456545Y-242547D02*
D03*
Y-228767D02*
D03*
Y-238610D02*
D03*
Y-240578D02*
D03*
Y-246484D02*
D03*
Y-258295D02*
D03*
Y-252389D02*
D03*
Y-222862D02*
D03*
Y-232704D02*
D03*
Y-226799D02*
D03*
Y-260263D02*
D03*
X440601Y-220893D02*
D03*
X456545Y-218925D02*
D03*
Y-248452D02*
D03*
Y-262232D02*
D03*
X440601Y-222862D02*
D03*
Y-216956D02*
D03*
Y-226799D02*
D03*
X456545Y-216956D02*
D03*
X440601Y-232704D02*
D03*
X456545Y-256326D02*
D03*
Y-250421D02*
D03*
X440601Y-236641D02*
D03*
X456545Y-289791D02*
D03*
X440601D02*
D03*
Y-224830D02*
D03*
Y-234673D02*
D03*
Y-244515D02*
D03*
Y-254358D02*
D03*
Y-264200D02*
D03*
Y-274043D02*
D03*
Y-283885D02*
D03*
X456545Y-224830D02*
D03*
Y-234673D02*
D03*
Y-244515D02*
D03*
Y-254358D02*
D03*
Y-264200D02*
D03*
Y-274043D02*
D03*
Y-283885D02*
D03*
Y-293728D02*
D03*
X440601D02*
D03*
Y-291759D02*
D03*
Y-238610D02*
D03*
X456545Y-291759D02*
D03*
D197*
X209193Y-252680D02*
D03*
X224941D02*
D03*
X209193Y-250680D02*
D03*
X224941D02*
D03*
X209193Y-248680D02*
D03*
X224941D02*
D03*
X209193Y-246680D02*
D03*
X224941D02*
D03*
X209193Y-244680D02*
D03*
X224941D02*
D03*
X209193Y-242680D02*
D03*
X224941D02*
D03*
X209193Y-240680D02*
D03*
X224941D02*
D03*
X209193Y-238680D02*
D03*
X224941D02*
D03*
X209193Y-236680D02*
D03*
X224941D02*
D03*
Y-234680D02*
D03*
X209193D02*
D03*
Y-252680D02*
D03*
X224941D02*
D03*
X209193Y-250680D02*
D03*
X224941D02*
D03*
X209193Y-248680D02*
D03*
X224941D02*
D03*
X209193Y-246680D02*
D03*
X224941D02*
D03*
X209193Y-244680D02*
D03*
X224941D02*
D03*
X209193Y-242680D02*
D03*
X224941D02*
D03*
X209193Y-240680D02*
D03*
X224941D02*
D03*
X209193Y-238680D02*
D03*
X224941D02*
D03*
X209193Y-236680D02*
D03*
X224941D02*
D03*
Y-234680D02*
D03*
X209193D02*
D03*
D198*
X599213Y-28445D02*
D03*
Y-40059D02*
D03*
D199*
X27067Y-234842D02*
D03*
Y-232874D02*
D03*
Y-230906D02*
D03*
Y-228937D02*
D03*
X14665D02*
D03*
Y-230906D02*
D03*
Y-232874D02*
D03*
Y-234842D02*
D03*
X27067Y-187205D02*
D03*
Y-185236D02*
D03*
Y-183268D02*
D03*
Y-181299D02*
D03*
X14665D02*
D03*
Y-183268D02*
D03*
Y-185236D02*
D03*
Y-187205D02*
D03*
X27067Y-291929D02*
D03*
Y-289961D02*
D03*
Y-287992D02*
D03*
Y-286024D02*
D03*
X14665D02*
D03*
Y-287992D02*
D03*
Y-289961D02*
D03*
Y-291929D02*
D03*
X21949Y-344685D02*
D03*
Y-342717D02*
D03*
Y-340748D02*
D03*
Y-338779D02*
D03*
X9547D02*
D03*
Y-340748D02*
D03*
Y-342717D02*
D03*
Y-344685D02*
D03*
D200*
X1181Y-340945D02*
D03*
Y-335433D02*
D03*
X11417Y-225984D02*
D03*
Y-220472D02*
D03*
D201*
X14567Y-280709D02*
D03*
X9055D02*
D03*
X10236Y-175591D02*
D03*
X15748D02*
D03*
D202*
X281102Y-401427D02*
D03*
X159055D02*
D03*
X155118D02*
D03*
X151181D02*
D03*
X178740D02*
D03*
X222047D02*
D03*
X265354D02*
D03*
X261417D02*
D03*
X249606D02*
D03*
X245669D02*
D03*
X233858D02*
D03*
X229921D02*
D03*
X214173D02*
D03*
X210236D02*
D03*
X186614D02*
D03*
X182677D02*
D03*
X202362D02*
D03*
X273228D02*
D03*
X166929D02*
D03*
X170866D02*
D03*
X190551D02*
D03*
X269291D02*
D03*
X257480D02*
D03*
X241732D02*
D03*
X237795D02*
D03*
X174803D02*
D03*
X162992D02*
D03*
X253543D02*
D03*
X206299D02*
D03*
X218110D02*
D03*
X225984D02*
D03*
D203*
X277165Y-399477D02*
D03*
D204*
X590551Y-35472D02*
D03*
Y-40905D02*
D03*
D205*
X620079Y-266682D02*
D03*
X620078Y-293357D02*
D03*
D206*
X298031Y-115512D02*
D03*
Y-145512D02*
D03*
Y-125512D02*
D03*
Y-135512D02*
D03*
D207*
Y-155512D02*
D03*
D208*
X321260Y-145669D02*
D03*
Y-135669D02*
D03*
Y-125669D02*
D03*
D209*
Y-155669D02*
D03*
D210*
X603110Y-805D02*
D03*
D211*
X574409Y7445D02*
D03*
D212*
Y-9055D02*
D03*
X552709Y7445D02*
D03*
Y-9055D02*
D03*
D213*
X0Y0D02*
D03*
X0Y-378395D02*
D03*
D214*
X608268Y-288779D02*
D03*
Y-271260D02*
D03*
D215*
X620079Y-263583D02*
D03*
Y-296457D02*
D03*
D216*
X138297Y-22096D02*
D03*
Y-69340D02*
D03*
D03*
Y-53592D02*
D03*
X541093Y-320167D02*
D03*
X556841D02*
D03*
X509597D02*
D03*
X556841D02*
D03*
D217*
X194882Y394D02*
D03*
X496457Y-271358D02*
D03*
D218*
X194882Y-78347D02*
D03*
X575197Y-271358D02*
D03*
D219*
X354035Y-38976D02*
D03*
X424803D02*
D03*
X535827Y-112205D02*
D03*
D220*
X390462Y-181769D02*
D03*
X311722D02*
D03*
X390452Y-329890D02*
D03*
X311712D02*
D03*
X261082Y-294702D02*
D03*
Y-215962D02*
D03*
X448573Y-215972D02*
D03*
Y-294712D02*
D03*
D221*
X186221Y-334252D02*
D03*
X198031D02*
D03*
X58268Y-163779D02*
D03*
X209842Y-334252D02*
D03*
X58268Y-323622D02*
D03*
X218110Y-163779D02*
D03*
X58268Y-243701D02*
D03*
X174221Y-334252D02*
D03*
X218110Y-323622D02*
D03*
X162221Y-334252D02*
D03*
X174221D02*
D03*
X198031D02*
D03*
X209842D02*
D03*
X218110Y-163779D02*
D03*
Y-323622D02*
D03*
X58268D02*
D03*
Y-243701D02*
D03*
Y-163779D02*
D03*
X186221Y-334252D02*
D03*
X162221D02*
D03*
D222*
X200876Y-315719D02*
D03*
X75768Y-321622D02*
D03*
X78268Y-159780D02*
D03*
X200610Y-171879D02*
D03*
D223*
X453193Y-334056D02*
D03*
X256593Y-177056D02*
D03*
X256693Y-334056D02*
D03*
X453193Y-177056D02*
D03*
D224*
X-18464Y-326781D02*
D03*
X1535D02*
D03*
Y-306781D02*
D03*
X-18464D02*
D03*
X-18465Y-273630D02*
D03*
X1535D02*
D03*
Y-253630D02*
D03*
X-18465D02*
D03*
Y-220480D02*
D03*
X1535D02*
D03*
Y-200480D02*
D03*
X-18465D02*
D03*
X-18464Y-167332D02*
D03*
X1535D02*
D03*
Y-147332D02*
D03*
X-18464D02*
D03*
D225*
X-8465Y-316781D02*
D03*
X-8465Y-263630D02*
D03*
Y-210480D02*
D03*
X-8465Y-157332D02*
D03*
D226*
X609449Y-98189D02*
D03*
D227*
Y-108189D02*
D03*
Y-118189D02*
D03*
Y-128189D02*
D03*
Y-138189D02*
D03*
Y-148189D02*
D03*
X619449Y-98189D02*
D03*
Y-108189D02*
D03*
Y-118189D02*
D03*
Y-128189D02*
D03*
Y-138189D02*
D03*
Y-148189D02*
D03*
D228*
X181534Y-387757D02*
D03*
X522047Y-270866D02*
D03*
X496620Y-310492D02*
D03*
X61811Y787D02*
D03*
X593307Y-292126D02*
D03*
X245325Y-120837D02*
D03*
X500049Y-256633D02*
D03*
X585039Y-266142D02*
D03*
X560630Y-269291D02*
D03*
X599044Y-275032D02*
D03*
X585039Y-272835D02*
D03*
X581496D02*
D03*
X548425Y-269632D02*
D03*
X541093Y-284626D02*
D03*
X541411Y-269932D02*
D03*
X536489Y-269182D02*
D03*
X554724Y-272441D02*
D03*
X555460Y-284401D02*
D03*
X574406Y-280807D02*
D03*
X567525Y-286203D02*
D03*
X581890Y-290158D02*
D03*
X583815Y-275386D02*
D03*
X614822Y-250158D02*
D03*
X604724Y-274803D02*
D03*
X321260Y-166142D02*
D03*
X150394Y-140157D02*
D03*
X317323Y-114961D02*
D03*
X321260D02*
D03*
X309449Y-211811D02*
D03*
X313386Y-212598D02*
D03*
X124016Y-110236D02*
D03*
X222351Y-98694D02*
D03*
X245276Y-115748D02*
D03*
X211648Y-103695D02*
D03*
X44001Y-137747D02*
D03*
X57422Y-128927D02*
D03*
X89312Y-128140D02*
D03*
X84981D02*
D03*
X80651D02*
D03*
X89312Y-123809D02*
D03*
X84981D02*
D03*
X80651D02*
D03*
X89312Y-119478D02*
D03*
X84981D02*
D03*
X80651D02*
D03*
X58407Y-137589D02*
D03*
X44134Y-115080D02*
D03*
X44621Y-110628D02*
D03*
X58210Y-108061D02*
D03*
X139370Y-118898D02*
D03*
X262724Y-107813D02*
D03*
X253082Y-110236D02*
D03*
X317828Y-161260D02*
D03*
X313878Y-161597D02*
D03*
X286221Y-124803D02*
D03*
X285827Y-137795D02*
D03*
X285384Y-154492D02*
D03*
X284646Y-128347D02*
D03*
X284252Y-144095D02*
D03*
X282058Y-151217D02*
D03*
X281890Y-155905D02*
D03*
X281496Y-124409D02*
D03*
X280709Y-137795D02*
D03*
X276650Y-128810D02*
D03*
X276083Y-152559D02*
D03*
Y-141142D02*
D03*
X255906Y-126378D02*
D03*
Y-131496D02*
D03*
Y-137008D02*
D03*
Y-142126D02*
D03*
X257480Y-150394D02*
D03*
X255512Y-146850D02*
D03*
X140551Y-116535D02*
D03*
X364567Y-326378D02*
D03*
X357575Y-327776D02*
D03*
X357480Y-332677D02*
D03*
X350787Y-329921D02*
D03*
X205906Y-372441D02*
D03*
X211024D02*
D03*
X222835Y-372047D02*
D03*
X217323Y-371654D02*
D03*
X237795D02*
D03*
X242897Y-371864D02*
D03*
X250394Y-375984D02*
D03*
X259449Y-373228D02*
D03*
X268504Y-372047D02*
D03*
X274803Y-372441D02*
D03*
X266929Y-385039D02*
D03*
X243701Y-389370D02*
D03*
X250394Y-384646D02*
D03*
X227953Y-383858D02*
D03*
X233858Y-384646D02*
D03*
X213386D02*
D03*
X513386Y-199213D02*
D03*
X521654Y-198819D02*
D03*
X591339Y-189764D02*
D03*
X153225Y-121747D02*
D03*
X133099Y-136519D02*
D03*
X24500Y-8429D02*
D03*
X603150Y-235946D02*
D03*
X604316Y-246600D02*
D03*
X152756Y-65354D02*
D03*
X157480Y-73228D02*
D03*
X381890Y-183858D02*
D03*
X384646Y-184252D02*
D03*
X359842Y-161024D02*
D03*
X363386Y-160630D02*
D03*
X367717D02*
D03*
X454775Y-308565D02*
D03*
X569685Y-303150D02*
D03*
X608268Y-84252D02*
D03*
X383083Y-161839D02*
D03*
X421313Y-174784D02*
D03*
X396850Y-249016D02*
D03*
X129063Y-136618D02*
D03*
X38613Y-53355D02*
D03*
X172674Y-138386D02*
D03*
X613406Y-89494D02*
D03*
X388189Y-162205D02*
D03*
X419798Y-176745D02*
D03*
X401575Y-249213D02*
D03*
X126307Y-136224D02*
D03*
X38583Y-58355D02*
D03*
X170311Y-139961D02*
D03*
X491732Y-149213D02*
D03*
X500394Y-145669D02*
D03*
X496063Y-145276D02*
D03*
X491732D02*
D03*
X550391Y-243310D02*
D03*
X477165Y-247244D02*
D03*
X539370Y-228740D02*
D03*
X542913D02*
D03*
X561024Y-183465D02*
D03*
Y-186614D02*
D03*
X-4724Y-283071D02*
D03*
X35433Y-129528D02*
D03*
X32283D02*
D03*
X28740D02*
D03*
X35433Y-50787D02*
D03*
X149935Y-124206D02*
D03*
X150233Y-119882D02*
D03*
X429528Y-231496D02*
D03*
X364173Y-280315D02*
D03*
X464961Y-125197D02*
D03*
X50000Y-44094D02*
D03*
X324016Y-42913D02*
D03*
X318898Y-43307D02*
D03*
X324016Y-39764D02*
D03*
X318898D02*
D03*
X324016Y-35827D02*
D03*
X318898D02*
D03*
X505118Y-24016D02*
D03*
X500787Y-24409D02*
D03*
X496457Y-24016D02*
D03*
X505118Y-20079D02*
D03*
X500787D02*
D03*
X496457D02*
D03*
X245669Y-74016D02*
D03*
X246063Y-70079D02*
D03*
X241732Y-74016D02*
D03*
Y-70079D02*
D03*
X326772Y-73622D02*
D03*
X322441D02*
D03*
X317717Y-73228D02*
D03*
X326772Y-69291D02*
D03*
X322441D02*
D03*
X317717D02*
D03*
X427953Y-206299D02*
D03*
X481496Y-197244D02*
D03*
X468504Y-44488D02*
D03*
X463779D02*
D03*
X458661Y-44094D02*
D03*
X468898Y-39764D02*
D03*
X463779Y-39370D02*
D03*
X458661D02*
D03*
X295669Y-45276D02*
D03*
X290945D02*
D03*
X295276Y-40945D02*
D03*
X290945D02*
D03*
X295276Y-35433D02*
D03*
X290945D02*
D03*
X118504Y-40945D02*
D03*
X85039Y-77559D02*
D03*
X383465Y-234252D02*
D03*
X389764D02*
D03*
X386614Y-237402D02*
D03*
Y-231102D02*
D03*
X611811Y-221260D02*
D03*
X426772Y-179528D02*
D03*
X418898Y-245276D02*
D03*
X602105Y-99109D02*
D03*
X597244Y-108661D02*
D03*
X592913Y-116535D02*
D03*
X594488Y-132677D02*
D03*
X43701Y-34646D02*
D03*
X51287Y-126878D02*
D03*
X13386D02*
D03*
X29543Y-345214D02*
D03*
X240158Y-278740D02*
D03*
X26378Y-20472D02*
D03*
X24409Y-16535D02*
D03*
X26378Y-10630D02*
D03*
X35433Y15354D02*
D03*
X36220Y8268D02*
D03*
X35827Y1575D02*
D03*
X19685Y-2362D02*
D03*
X20079Y3937D02*
D03*
Y10630D02*
D03*
Y17323D02*
D03*
X298819Y-269685D02*
D03*
X391339Y-277953D02*
D03*
X299606Y-185433D02*
D03*
X231102Y-239764D02*
D03*
X230709Y-242913D02*
D03*
X399213Y-193307D02*
D03*
X204331Y-101575D02*
D03*
X432283Y-254724D02*
D03*
X496063Y-244094D02*
D03*
X173228Y-117323D02*
D03*
X261024Y-200394D02*
D03*
X381890Y-254331D02*
D03*
X318989Y-253024D02*
D03*
X337402Y-260630D02*
D03*
X429134Y-246850D02*
D03*
X483831Y-241339D02*
D03*
X488189Y-216535D02*
D03*
X500971Y-219896D02*
D03*
X470472Y-246457D02*
D03*
X476968Y-76378D02*
D03*
X462992D02*
D03*
X289370Y-205906D02*
D03*
X153150Y-113386D02*
D03*
X226378Y-32677D02*
D03*
X100394Y-30315D02*
D03*
X383071Y-276772D02*
D03*
X402756Y-281102D02*
D03*
X616929Y-225984D02*
D03*
X611614Y-186107D02*
D03*
X586221Y-178740D02*
D03*
X591339Y-144488D02*
D03*
X586614Y-158661D02*
D03*
X582165Y-163898D02*
D03*
X581890Y-174016D02*
D03*
X579134Y-214006D02*
D03*
X581890Y-235925D02*
D03*
X584646Y-225197D02*
D03*
X590188Y-221161D02*
D03*
X608661Y-220472D02*
D03*
X589370Y-212992D02*
D03*
X588922Y-206462D02*
D03*
X583858Y-192913D02*
D03*
X589370Y-201575D02*
D03*
X27559Y-337402D02*
D03*
X341339Y-277953D02*
D03*
X407874Y-216535D02*
D03*
X408760Y-238189D02*
D03*
X462473Y-277635D02*
D03*
X321850Y-283465D02*
D03*
X461417Y-305118D02*
D03*
X598397Y-88288D02*
D03*
X603543Y-87795D02*
D03*
X135433Y-79134D02*
D03*
X424409Y-205512D02*
D03*
X428346Y-187795D02*
D03*
X140070Y-132385D02*
D03*
X140116Y-124048D02*
D03*
X141339Y394D02*
D03*
X180610Y-87795D02*
D03*
X198524D02*
D03*
X197244Y-102756D02*
D03*
X181004Y-101181D02*
D03*
X177559Y-87795D02*
D03*
X197638Y-97638D02*
D03*
X182283Y-97244D02*
D03*
X182677Y-94488D02*
D03*
X189764Y-88189D02*
D03*
Y-100787D02*
D03*
X196850Y-94488D02*
D03*
X161417Y-25984D02*
D03*
X169291Y13386D02*
D03*
Y9646D02*
D03*
X159843D02*
D03*
X151181Y14173D02*
D03*
X142520Y13189D02*
D03*
X144685Y-11811D02*
D03*
X162598Y-9449D02*
D03*
X153543Y-10433D02*
D03*
X162598Y-13189D02*
D03*
Y-1575D02*
D03*
X151181Y18110D02*
D03*
X137598Y-6299D02*
D03*
X134055D02*
D03*
X149803Y-9238D02*
D03*
X150000Y-787D02*
D03*
X151782Y10443D02*
D03*
X473303Y-276476D02*
D03*
X479331Y-294626D02*
D03*
X487402Y-256988D02*
D03*
X485827Y-279429D02*
D03*
X476772Y-254035D02*
D03*
X473622Y-259055D02*
D03*
X476378Y-273622D02*
D03*
X486221Y-265748D02*
D03*
X474409D02*
D03*
X480315Y-259744D02*
D03*
Y-271752D02*
D03*
X548819Y-300787D02*
D03*
X489567Y-310236D02*
D03*
X492323Y-303543D02*
D03*
X495866D02*
D03*
X483465Y-291535D02*
D03*
X476772Y-291929D02*
D03*
X466142Y-294685D02*
D03*
Y-298228D02*
D03*
X461417Y-312099D02*
D03*
X473819Y-315354D02*
D03*
X484842Y-317717D02*
D03*
X493110Y-310236D02*
D03*
X461024Y-302756D02*
D03*
X498425Y-307087D02*
D03*
X478346Y-305118D02*
D03*
X477362Y-313767D02*
D03*
X596865Y-266396D02*
D03*
X594765D02*
D03*
X624938Y-196373D02*
D03*
X624926Y-201353D02*
D03*
X624938Y-206373D02*
D03*
X624918Y-211353D02*
D03*
X625079Y-173898D02*
D03*
X624685Y-163898D02*
D03*
X551968Y-297638D02*
D03*
X127165Y-12598D02*
D03*
X118110Y-36220D02*
D03*
X117717Y-47293D02*
D03*
X121653Y-31496D02*
D03*
X404493Y-224149D02*
D03*
X404626Y-219685D02*
D03*
X578332Y-261235D02*
D03*
X507874Y-255906D02*
D03*
X534814Y-297190D02*
D03*
X528960Y-296841D02*
D03*
X495276Y-298130D02*
D03*
X503346Y-297967D02*
D03*
X507480Y-298130D02*
D03*
X501181D02*
D03*
X516929D02*
D03*
X522835Y-297736D02*
D03*
X540945Y-297342D02*
D03*
X546457D02*
D03*
X562205Y-297736D02*
D03*
X568110D02*
D03*
X570472D02*
D03*
X576378D02*
D03*
X571260Y-256791D02*
D03*
X568898D02*
D03*
X550000Y-255610D02*
D03*
X540945Y-256004D02*
D03*
X538976Y-250886D02*
D03*
X536614Y-245374D02*
D03*
X518110Y-255217D02*
D03*
X522047Y-249705D02*
D03*
X524016Y-243799D02*
D03*
X502362Y-257185D02*
D03*
X504331D02*
D03*
X513386Y-254429D02*
D03*
X508268Y-251673D02*
D03*
X564173Y-255906D02*
D03*
X494882Y-262303D02*
D03*
X495669Y-255512D02*
D03*
X209449Y7087D02*
D03*
X203937Y1969D02*
D03*
X214173Y1181D02*
D03*
Y-79134D02*
D03*
X205118Y-79380D02*
D03*
X214567Y-11417D02*
D03*
X211811Y-16535D02*
D03*
X209055Y-7480D02*
D03*
Y-5512D02*
D03*
X209449Y-3543D02*
D03*
X216535Y-25197D02*
D03*
X211024Y-21260D02*
D03*
X220866Y-39764D02*
D03*
X215354Y-42126D02*
D03*
X210236Y-44094D02*
D03*
X210630Y-53150D02*
D03*
X209541Y-58689D02*
D03*
X209449Y-72047D02*
D03*
Y-74410D02*
D03*
X168504Y-79528D02*
D03*
Y-73622D02*
D03*
Y-71260D02*
D03*
Y-65354D02*
D03*
X168898Y-49606D02*
D03*
Y-44094D02*
D03*
X168504Y-37795D02*
D03*
Y-31890D02*
D03*
Y-25984D02*
D03*
X168110Y-20079D02*
D03*
Y-4331D02*
D03*
Y-10630D02*
D03*
X168273Y-6496D02*
D03*
X168110Y1575D02*
D03*
X101181Y-38583D02*
D03*
X144095Y-80315D02*
D03*
X149606D02*
D03*
X117323Y-65354D02*
D03*
X121467Y-74575D02*
D03*
X-18601Y-349409D02*
D03*
X87795Y-99606D02*
D03*
X540551Y-340945D02*
D03*
X535827Y-345276D02*
D03*
X555512Y-340158D02*
D03*
X544882Y-336221D02*
D03*
X552756Y-335827D02*
D03*
X561024Y-340158D02*
D03*
X568898Y-319009D02*
D03*
X570079Y-309921D02*
D03*
X552756Y-305118D02*
D03*
X544882D02*
D03*
X536221Y-300787D02*
D03*
X530709D02*
D03*
X530315Y-338976D02*
D03*
X513406Y-302902D02*
D03*
X521654Y-336221D02*
D03*
X513386D02*
D03*
X505410Y-336036D02*
D03*
X505512Y-303150D02*
D03*
X455118Y-92520D02*
D03*
X460236Y-87795D02*
D03*
Y-92520D02*
D03*
X454724Y-87795D02*
D03*
X624409Y-31496D02*
D03*
X620079Y-31890D02*
D03*
X615748Y-32283D02*
D03*
X611417Y-33071D02*
D03*
X620866Y-35827D02*
D03*
X611811Y-38189D02*
D03*
X601181Y-23622D02*
D03*
X597244D02*
D03*
Y-29921D02*
D03*
X601181Y-26772D02*
D03*
Y-29921D02*
D03*
X597244Y-26772D02*
D03*
X542913Y-72835D02*
D03*
Y-69291D02*
D03*
Y-65748D02*
D03*
Y-61811D02*
D03*
Y-58268D02*
D03*
X595276Y-79921D02*
D03*
X608405Y-70079D02*
D03*
X618110Y-62205D02*
D03*
X616142Y-47638D02*
D03*
X618898Y-50787D02*
D03*
X613386D02*
D03*
X609547Y-51181D02*
D03*
X606693Y-50787D02*
D03*
X601575Y-53543D02*
D03*
X599213Y-50000D02*
D03*
X544095Y-42126D02*
D03*
X539764D02*
D03*
X534646Y-51968D02*
D03*
X534252Y-48425D02*
D03*
X534646Y-45276D02*
D03*
Y-42126D02*
D03*
X238189Y-107087D02*
D03*
X233071D02*
D03*
X223228Y-107480D02*
D03*
X228346D02*
D03*
X238189Y-138976D02*
D03*
X233209Y-139232D02*
D03*
X228209Y-138721D02*
D03*
X217405Y-138189D02*
D03*
X223209Y-137815D02*
D03*
X214173Y-107087D02*
D03*
X192126Y-111811D02*
D03*
X199193Y-105925D02*
D03*
X204193Y-138257D02*
D03*
X199193Y-138680D02*
D03*
X130245Y-120870D02*
D03*
X133099Y-119984D02*
D03*
X148425Y-104336D02*
D03*
X153150Y-103412D02*
D03*
Y-99691D02*
D03*
X158268Y-107480D02*
D03*
X168110Y-103937D02*
D03*
Y-100132D02*
D03*
X161417Y-95276D02*
D03*
Y-107480D02*
D03*
X178185Y-136811D02*
D03*
Y-133661D02*
D03*
X150627Y-130512D02*
D03*
X150233Y-127362D02*
D03*
X152904Y-124213D02*
D03*
X152398Y-117717D02*
D03*
X156926Y-111614D02*
D03*
X164843Y-114040D02*
D03*
X160075Y-112402D02*
D03*
X168343Y-110827D02*
D03*
X186847Y-135236D02*
D03*
X188028Y-113583D02*
D03*
X189209Y-131339D02*
D03*
Y-117480D02*
D03*
X173461Y-127362D02*
D03*
X165587Y-139961D02*
D03*
X151808Y-137205D02*
D03*
X162241Y-140004D02*
D03*
X106693Y15354D02*
D03*
X107087Y9449D02*
D03*
X111024D02*
D03*
Y15354D02*
D03*
X105512Y-79921D02*
D03*
X109843D02*
D03*
Y-74410D02*
D03*
X105512D02*
D03*
X99606Y-63779D02*
D03*
X107874D02*
D03*
Y-59842D02*
D03*
X99606D02*
D03*
X74616Y-61723D02*
D03*
X56693Y1060D02*
D03*
X39764Y-29528D02*
D03*
Y-25984D02*
D03*
X35731Y-9843D02*
D03*
Y-18898D02*
D03*
X47441Y-27362D02*
D03*
Y-21260D02*
D03*
Y-5709D02*
D03*
Y-11811D02*
D03*
X75394Y-5709D02*
D03*
Y-11811D02*
D03*
X66142D02*
D03*
X61417D02*
D03*
X56693D02*
D03*
Y-16535D02*
D03*
X61417D02*
D03*
X66142D02*
D03*
Y-21260D02*
D03*
X61417D02*
D03*
X52362Y-35531D02*
D03*
X61417Y-35741D02*
D03*
X37402Y-43355D02*
D03*
X38382Y-48355D02*
D03*
X66102Y-64085D02*
D03*
X72795Y-53355D02*
D03*
X86614Y-56299D02*
D03*
X91339Y-35039D02*
D03*
X86614Y-39370D02*
D03*
X88583Y-53937D02*
D03*
X85039D02*
D03*
X88583Y-50787D02*
D03*
X85039D02*
D03*
X88583Y-46457D02*
D03*
X85039Y-46850D02*
D03*
X84252Y-9055D02*
D03*
Y-5906D02*
D03*
Y-2362D02*
D03*
X88257Y-2500D02*
D03*
X93608Y-3379D02*
D03*
X90158Y-7480D02*
D03*
X107832Y-10197D02*
D03*
X97408D02*
D03*
X106693Y-27559D02*
D03*
X105282Y-19291D02*
D03*
X85827Y-16929D02*
D03*
X85853Y-13780D02*
D03*
X78740Y18110D02*
D03*
Y15354D02*
D03*
Y9843D02*
D03*
Y6693D02*
D03*
Y3543D02*
D03*
X110589Y1589D02*
D03*
X108268Y394D02*
D03*
X112598D02*
D03*
X116929Y-21654D02*
D03*
X118898Y-16929D02*
D03*
X366043Y-153937D02*
D03*
X373228Y-162598D02*
D03*
X378346Y-161811D02*
D03*
X388713Y-128731D02*
D03*
X383083Y-128504D02*
D03*
X336221Y-122047D02*
D03*
X333465D02*
D03*
X330315Y-121653D02*
D03*
X335827Y-164173D02*
D03*
X333071D02*
D03*
X329919Y-164008D02*
D03*
X329656Y-142480D02*
D03*
X329722Y-145827D02*
D03*
X347638Y-119882D02*
D03*
X347244Y-113189D02*
D03*
X355035Y-105876D02*
D03*
X390654Y-104510D02*
D03*
X383465Y-103543D02*
D03*
X369685Y-123622D02*
D03*
Y-120866D02*
D03*
Y-118110D02*
D03*
X366929Y-123622D02*
D03*
Y-120866D02*
D03*
X363779Y-123622D02*
D03*
X366929Y-118110D02*
D03*
X363779Y-120866D02*
D03*
Y-118110D02*
D03*
X448425Y-165354D02*
D03*
X451968D02*
D03*
X455512D02*
D03*
X458661D02*
D03*
X442815Y-161747D02*
D03*
Y-165847D02*
D03*
X439561D02*
D03*
X425984Y-109843D02*
D03*
X425630Y-112894D02*
D03*
X416535Y-120768D02*
D03*
X423622Y-115354D02*
D03*
X436811Y-153543D02*
D03*
X418110D02*
D03*
X422835D02*
D03*
X427559D02*
D03*
Y-148819D02*
D03*
X418110D02*
D03*
X422835D02*
D03*
Y-144095D02*
D03*
X418110D02*
D03*
X422835Y-131791D02*
D03*
X427843Y-166966D02*
D03*
X422835Y-166284D02*
D03*
X406693Y-125984D02*
D03*
X408268Y-124409D02*
D03*
Y-122047D02*
D03*
X400984Y-127102D02*
D03*
X415748Y-129609D02*
D03*
X418898Y-129753D02*
D03*
X445276Y-103543D02*
D03*
X444488Y-106299D02*
D03*
X440945Y-105905D02*
D03*
X436221Y-106299D02*
D03*
X434347Y-103743D02*
D03*
X434646Y-100787D02*
D03*
X431496Y-100000D02*
D03*
X422047Y-101969D02*
D03*
X418898Y-100000D02*
D03*
X445669Y-128347D02*
D03*
X449606D02*
D03*
Y-124803D02*
D03*
Y-121653D02*
D03*
X275590Y-199606D02*
D03*
X289370Y-200394D02*
D03*
X274803Y-188583D02*
D03*
X291831Y-197012D02*
D03*
X295669Y-191339D02*
D03*
X292815Y-187106D02*
D03*
X275590Y-184252D02*
D03*
X281890Y-188583D02*
D03*
Y-200771D02*
D03*
X288583Y-195276D02*
D03*
X275503D02*
D03*
X596063Y-239895D02*
D03*
Y-241995D02*
D03*
X321654Y-232677D02*
D03*
X336614Y-286221D02*
D03*
X315945Y-287795D02*
D03*
X315333Y-299430D02*
D03*
X336811Y-299399D02*
D03*
X313386Y-283465D02*
D03*
X308268Y-300000D02*
D03*
X324184Y-302194D02*
D03*
X356693Y-288583D02*
D03*
X355741Y-296063D02*
D03*
X314961Y-293701D02*
D03*
X320472Y-299569D02*
D03*
X325776Y-293701D02*
D03*
X320472Y-287865D02*
D03*
X345161Y-292913D02*
D03*
X333465D02*
D03*
X339370Y-286162D02*
D03*
Y-298819D02*
D03*
X329134Y-228740D02*
D03*
X341274Y-242913D02*
D03*
X340786Y-235827D02*
D03*
X312322Y-236221D02*
D03*
X309782Y-243307D02*
D03*
X334842Y-247244D02*
D03*
X319685Y-245276D02*
D03*
X333714Y-239764D02*
D03*
X325590Y-246324D02*
D03*
Y-232344D02*
D03*
X317009Y-239764D02*
D03*
X390896Y-249065D02*
D03*
X386615Y-249113D02*
D03*
X400000Y-219291D02*
D03*
X398472Y-235531D02*
D03*
X378937Y-249803D02*
D03*
X367654Y-236614D02*
D03*
X373093Y-232972D02*
D03*
X375197Y-221260D02*
D03*
X382776Y-221555D02*
D03*
X368232Y-217717D02*
D03*
X390158D02*
D03*
X415623Y-358391D02*
D03*
X414772Y-353273D02*
D03*
X449150Y-355832D02*
D03*
X460678Y-359179D02*
D03*
X460900Y-354061D02*
D03*
X493234Y-356620D02*
D03*
X533931Y-356296D02*
D03*
X499525Y-358855D02*
D03*
X499302Y-353737D02*
D03*
X579072Y-356690D02*
D03*
X561330Y-356099D02*
D03*
X543698Y-358659D02*
D03*
X543718Y-353540D02*
D03*
X626987Y-228346D02*
D03*
X605512Y-261024D02*
D03*
Y-256693D02*
D03*
X622835Y-244094D02*
D03*
Y-235433D02*
D03*
X618504Y-252362D02*
D03*
X622101Y-250000D02*
D03*
X622803Y-241006D02*
D03*
X605317Y-252756D02*
D03*
X610236Y-300000D02*
D03*
X619148Y-302756D02*
D03*
X622221Y-313481D02*
D03*
X622753Y-353307D02*
D03*
X622677Y-333307D02*
D03*
X623228Y-343307D02*
D03*
X598583Y-353307D02*
D03*
X598819Y-343307D02*
D03*
X598959Y-333307D02*
D03*
X598898Y-313307D02*
D03*
X393701Y-168898D02*
D03*
X378594Y-166966D02*
D03*
X348031Y-165748D02*
D03*
X342808Y-166966D02*
D03*
X337795Y-181102D02*
D03*
X334252Y-180315D02*
D03*
X310236Y-165748D02*
D03*
X309055Y-195669D02*
D03*
X314675Y-198819D02*
D03*
X319291Y-196850D02*
D03*
X373730Y-202888D02*
D03*
X375698Y-197700D02*
D03*
X383572Y-206205D02*
D03*
X385541Y-202460D02*
D03*
X155427Y-33907D02*
D03*
X155328Y-26033D02*
D03*
X122539D02*
D03*
X142126Y-348031D02*
D03*
X141587Y-352161D02*
D03*
X22047Y-335433D02*
D03*
X2097Y-349213D02*
D03*
X27067Y-282677D02*
D03*
X5584Y-238905D02*
D03*
X35120Y-228937D02*
D03*
X10630Y-197638D02*
D03*
X22441Y-167323D02*
D03*
X19685D02*
D03*
X16929D02*
D03*
X23228Y-147244D02*
D03*
X20079D02*
D03*
X17323D02*
D03*
X27165Y-179134D02*
D03*
X26772Y-348819D02*
D03*
X-1181Y-352831D02*
D03*
X4331Y-344488D02*
D03*
X12598Y-349213D02*
D03*
X35039Y-289961D02*
D03*
Y-285827D02*
D03*
X27067Y-298727D02*
D03*
X10630Y-292126D02*
D03*
X14173Y-294320D02*
D03*
X288Y-234968D02*
D03*
X10007D02*
D03*
X19685Y-239370D02*
D03*
X14665Y-237402D02*
D03*
X36220Y-235039D02*
D03*
X36614Y-232677D02*
D03*
X35039Y-237402D02*
D03*
X30709Y-190411D02*
D03*
X33071Y-185755D02*
D03*
X35827D02*
D03*
X13780Y-190551D02*
D03*
X9843Y-185755D02*
D03*
X19682Y-192520D02*
D03*
X198392Y-366842D02*
D03*
X196701Y-370523D02*
D03*
X394193Y-197670D02*
D03*
X380363Y-196740D02*
D03*
X230165Y-235119D02*
D03*
X230406Y-251861D02*
D03*
X230251Y-232266D02*
D03*
D229*
X127392Y-94557D02*
D03*
X365581Y7806D02*
D03*
Y-94557D02*
D03*
X127392Y7806D02*
D03*
X479695Y-331073D02*
D03*
X582058Y-92884D02*
D03*
X479695D02*
D03*
X582058Y-331073D02*
D03*
M02*
